(kicad_sch
	(version 20250114)
	(generator "eeschema")
	(generator_version "9.0")
	(paper "A3")
	(title_block
		(title "Antmicro Baseboard for Jetson AGX Thor")
		(date "2026-02-17")
		(rev "1.1.0")
		(company "Antmicro Ltd")
		(comment 1 "www.antmicro.com")
	)
	(text "Switch between RP and EP\nconfiguration"
		(exclude_from_sim no)
		(at 31.496 66.802 0)
		(effects
			(font
				(size 1.27 1.27)
			)
		)
	)
	(text "DP and CSI SOM connections"
		(exclude_from_sim no)
		(at 311.15 20.574 0)
		(effects
			(font
				(size 2.54 2.54)
				(thickness 0.508)
				(bold yes)
			)
			(justify left bottom)
		)
	)
	(text "Reference clocks"
		(exclude_from_sim no)
		(at 226.568 217.932 0)
		(effects
			(font
				(size 2.54 2.54)
				(thickness 0.508)
				(bold yes)
			)
			(justify left bottom)
		)
	)
	(text "PCIe and USB3.0 SOM connections"
		(exclude_from_sim no)
		(at 74.422 21.336 0)
		(effects
			(font
				(size 2.54 2.54)
				(thickness 0.508)
				(bold yes)
			)
			(justify left bottom)
		)
	)
	(text "JTAG Debug"
		(exclude_from_sim no)
		(at 83.058 217.678 0)
		(effects
			(font
				(size 2.54 2.54)
				(thickness 0.508)
				(bold yes)
			)
			(justify left bottom)
		)
	)
	(junction
		(at 60.96 77.47)
		(diameter 0)
		(color 0 0 0 0)
	)
	(junction
		(at 116.84 262.89)
		(diameter 0)
		(color 0 0 0 0)
	)
	(junction
		(at 142.24 273.05)
		(diameter 0)
		(color 0 0 0 0)
	)
	(junction
		(at 74.93 233.68)
		(diameter 0)
		(color 0 0 0 0)
	)
	(junction
		(at 69.85 252.73)
		(diameter 0)
		(color 0 0 0 0)
	)
	(junction
		(at 274.32 234.95)
		(diameter 0)
		(color 0 0 0 0)
	)
	(junction
		(at 274.32 262.89)
		(diameter 0)
		(color 0 0 0 0)
	)
	(junction
		(at 130.81 264.16)
		(diameter 0)
		(color 0 0 0 0)
	)
	(junction
		(at 205.74 234.95)
		(diameter 0)
		(color 0 0 0 0)
	)
	(junction
		(at 266.7 265.43)
		(diameter 0)
		(color 0 0 0 0)
	)
	(junction
		(at 101.6 233.68)
		(diameter 0)
		(color 0 0 0 0)
	)
	(junction
		(at 209.55 262.89)
		(diameter 0)
		(color 0 0 0 0)
	)
	(junction
		(at 266.7 237.49)
		(diameter 0)
		(color 0 0 0 0)
	)
	(junction
		(at 66.04 223.52)
		(diameter 0)
		(color 0 0 0 0)
	)
	(junction
		(at 135.89 243.84)
		(diameter 0)
		(color 0 0 0 0)
	)
	(junction
		(at 209.55 234.95)
		(diameter 0)
		(color 0 0 0 0)
	)
	(junction
		(at 59.69 74.93)
		(diameter 0)
		(color 0 0 0 0)
	)
	(junction
		(at 115.57 233.68)
		(diameter 0)
		(color 0 0 0 0)
	)
	(junction
		(at 205.74 262.89)
		(diameter 0)
		(color 0 0 0 0)
	)
	(no_connect
		(at 81.28 184.15)
	)
	(no_connect
		(at 121.92 176.53)
	)
	(no_connect
		(at 313.69 224.79)
	)
	(no_connect
		(at 364.49 232.41)
	)
	(no_connect
		(at 125.73 87.63)
	)
	(no_connect
		(at 78.74 57.15)
	)
	(no_connect
		(at 121.92 179.07)
	)
	(no_connect
		(at 121.92 189.23)
	)
	(no_connect
		(at 355.6 168.91)
	)
	(no_connect
		(at 313.69 245.11)
	)
	(no_connect
		(at 364.49 229.87)
	)
	(no_connect
		(at 81.28 179.07)
	)
	(no_connect
		(at 121.92 194.31)
	)
	(no_connect
		(at 121.92 186.69)
	)
	(no_connect
		(at 313.69 237.49)
	)
	(no_connect
		(at 313.69 242.57)
	)
	(no_connect
		(at 81.28 130.81)
	)
	(no_connect
		(at 121.92 133.35)
	)
	(no_connect
		(at 364.49 234.95)
	)
	(no_connect
		(at 307.34 35.56)
	)
	(no_connect
		(at 125.73 45.72)
	)
	(no_connect
		(at 78.74 54.61)
	)
	(no_connect
		(at 81.28 194.31)
	)
	(no_connect
		(at 313.69 227.33)
	)
	(no_connect
		(at 81.28 133.35)
	)
	(no_connect
		(at 81.28 186.69)
	)
	(no_connect
		(at 125.73 60.96)
	)
	(no_connect
		(at 313.69 229.87)
	)
	(no_connect
		(at 321.31 201.93)
	)
	(no_connect
		(at 321.31 199.39)
	)
	(no_connect
		(at 313.69 234.95)
	)
	(no_connect
		(at 81.28 189.23)
	)
	(no_connect
		(at 321.31 168.91)
	)
	(no_connect
		(at 121.92 181.61)
	)
	(no_connect
		(at 121.92 184.15)
	)
	(no_connect
		(at 78.74 52.07)
	)
	(no_connect
		(at 313.69 232.41)
	)
	(no_connect
		(at 313.69 240.03)
	)
	(no_connect
		(at 125.73 76.2)
	)
	(no_connect
		(at 364.49 237.49)
	)
	(no_connect
		(at 364.49 242.57)
	)
	(no_connect
		(at 168.91 241.3)
	)
	(no_connect
		(at 81.28 196.85)
	)
	(no_connect
		(at 81.28 181.61)
	)
	(no_connect
		(at 364.49 227.33)
	)
	(no_connect
		(at 355.6 166.37)
	)
	(no_connect
		(at 121.92 196.85)
	)
	(no_connect
		(at 364.49 240.03)
	)
	(no_connect
		(at 78.74 49.53)
	)
	(no_connect
		(at 364.49 224.79)
	)
	(no_connect
		(at 81.28 176.53)
	)
	(no_connect
		(at 125.73 48.26)
	)
	(no_connect
		(at 355.6 199.39)
	)
	(no_connect
		(at 125.73 90.17)
	)
	(no_connect
		(at 321.31 166.37)
	)
	(no_connect
		(at 355.6 201.93)
	)
	(no_connect
		(at 121.92 130.81)
	)
	(bus_entry
		(at 218.44 116.84)
		(size -1.27 1.27)
		(stroke
			(width 0)
			(type default)
		)
	)
	(bus_entry
		(at 179.07 110.49)
		(size -1.27 1.27)
		(stroke
			(width 0)
			(type default)
		)
	)
	(bus_entry
		(at 199.39 83.82)
		(size -1.27 1.27)
		(stroke
			(width 0)
			(type default)
		)
	)
	(bus_entry
		(at 374.65 203.2)
		(size -1.27 1.27)
		(stroke
			(width 0)
			(type default)
		)
	)
	(bus_entry
		(at 179.07 116.84)
		(size -1.27 1.27)
		(stroke
			(width 0)
			(type default)
		)
	)
	(bus_entry
		(at 262.89 73.66)
		(size 1.27 1.27)
		(stroke
			(width 0)
			(type default)
		)
	)
	(bus_entry
		(at 179.07 123.19)
		(size -1.27 1.27)
		(stroke
			(width 0)
			(type default)
		)
	)
	(bus_entry
		(at 199.39 72.39)
		(size -1.27 1.27)
		(stroke
			(width 0)
			(type default)
		)
	)
	(bus_entry
		(at 218.44 168.91)
		(size -1.27 1.27)
		(stroke
			(width 0)
			(type default)
		)
	)
	(bus_entry
		(at 374.65 194.31)
		(size -1.27 1.27)
		(stroke
			(width 0)
			(type default)
		)
	)
	(bus_entry
		(at 302.26 205.74)
		(size 1.27 1.27)
		(stroke
			(width 0)
			(type default)
		)
	)
	(bus_entry
		(at 199.39 57.15)
		(size -1.27 1.27)
		(stroke
			(width 0)
			(type default)
		)
	)
	(bus_entry
		(at 68.58 41.91)
		(size -1.27 -1.27)
		(stroke
			(width 0)
			(type default)
		)
	)
	(bus_entry
		(at 394.97 109.22)
		(size -1.27 1.27)
		(stroke
			(width 0)
			(type default)
		)
	)
	(bus_entry
		(at 394.97 132.08)
		(size -1.27 1.27)
		(stroke
			(width 0)
			(type default)
		)
	)
	(bus_entry
		(at 262.89 78.74)
		(size 1.27 1.27)
		(stroke
			(width 0)
			(type default)
		)
	)
	(bus_entry
		(at 179.07 104.14)
		(size -1.27 1.27)
		(stroke
			(width 0)
			(type default)
		)
	)
	(bus_entry
		(at 262.89 99.06)
		(size 1.27 1.27)
		(stroke
			(width 0)
			(type default)
		)
	)
	(bus_entry
		(at 199.39 81.28)
		(size -1.27 1.27)
		(stroke
			(width 0)
			(type default)
		)
	)
	(bus_entry
		(at 218.44 176.53)
		(size -1.27 1.27)
		(stroke
			(width 0)
			(type default)
		)
	)
	(bus_entry
		(at 179.07 193.04)
		(size -1.27 1.27)
		(stroke
			(width 0)
			(type default)
		)
	)
	(bus_entry
		(at 394.97 116.84)
		(size -1.27 1.27)
		(stroke
			(width 0)
			(type default)
		)
	)
	(bus_entry
		(at 199.39 50.8)
		(size -1.27 1.27)
		(stroke
			(width 0)
			(type default)
		)
	)
	(bus_entry
		(at 179.07 180.34)
		(size -1.27 1.27)
		(stroke
			(width 0)
			(type default)
		)
	)
	(bus_entry
		(at 262.89 127)
		(size 1.27 1.27)
		(stroke
			(width 0)
			(type default)
		)
	)
	(bus_entry
		(at 199.39 74.93)
		(size -1.27 1.27)
		(stroke
			(width 0)
			(type default)
		)
	)
	(bus_entry
		(at 302.26 208.28)
		(size 1.27 1.27)
		(stroke
			(width 0)
			(type default)
		)
	)
	(bus_entry
		(at 374.65 175.26)
		(size -1.27 1.27)
		(stroke
			(width 0)
			(type default)
		)
	)
	(bus_entry
		(at 262.89 116.84)
		(size 1.27 1.27)
		(stroke
			(width 0)
			(type default)
		)
	)
	(bus_entry
		(at 218.44 151.13)
		(size -1.27 1.27)
		(stroke
			(width 0)
			(type default)
		)
	)
	(bus_entry
		(at 262.89 124.46)
		(size 1.27 1.27)
		(stroke
			(width 0)
			(type default)
		)
	)
	(bus_entry
		(at 374.65 210.82)
		(size -1.27 1.27)
		(stroke
			(width 0)
			(type default)
		)
	)
	(bus_entry
		(at 179.07 187.96)
		(size -1.27 1.27)
		(stroke
			(width 0)
			(type default)
		)
	)
	(bus_entry
		(at 179.07 176.53)
		(size -1.27 1.27)
		(stroke
			(width 0)
			(type default)
		)
	)
	(bus_entry
		(at 262.89 134.62)
		(size 1.27 1.27)
		(stroke
			(width 0)
			(type default)
		)
	)
	(bus_entry
		(at 199.39 59.69)
		(size -1.27 1.27)
		(stroke
			(width 0)
			(type default)
		)
	)
	(bus_entry
		(at 394.97 91.44)
		(size -1.27 1.27)
		(stroke
			(width 0)
			(type default)
		)
	)
	(bus_entry
		(at 374.65 177.8)
		(size -1.27 1.27)
		(stroke
			(width 0)
			(type default)
		)
	)
	(bus_entry
		(at 262.89 121.92)
		(size 1.27 1.27)
		(stroke
			(width 0)
			(type default)
		)
	)
	(bus_entry
		(at 302.26 151.13)
		(size 1.27 1.27)
		(stroke
			(width 0)
			(type default)
		)
	)
	(bus_entry
		(at 302.26 189.23)
		(size 1.27 1.27)
		(stroke
			(width 0)
			(type default)
		)
	)
	(bus_entry
		(at 394.97 66.04)
		(size -1.27 1.27)
		(stroke
			(width 0)
			(type default)
		)
	)
	(bus_entry
		(at 199.39 68.58)
		(size -1.27 1.27)
		(stroke
			(width 0)
			(type default)
		)
	)
	(bus_entry
		(at 137.16 41.91)
		(size 1.27 -1.27)
		(stroke
			(width 0)
			(type default)
		)
	)
	(bus_entry
		(at 374.65 170.18)
		(size -1.27 1.27)
		(stroke
			(width 0)
			(type default)
		)
	)
	(bus_entry
		(at 218.44 113.03)
		(size -1.27 1.27)
		(stroke
			(width 0)
			(type default)
		)
	)
	(bus_entry
		(at 262.89 40.64)
		(size 1.27 1.27)
		(stroke
			(width 0)
			(type default)
		)
	)
	(bus_entry
		(at 179.07 166.37)
		(size -1.27 1.27)
		(stroke
			(width 0)
			(type default)
		)
	)
	(bus_entry
		(at 262.89 76.2)
		(size 1.27 1.27)
		(stroke
			(width 0)
			(type default)
		)
	)
	(bus_entry
		(at 218.44 119.38)
		(size -1.27 1.27)
		(stroke
			(width 0)
			(type default)
		)
	)
	(bus_entry
		(at 199.39 66.04)
		(size -1.27 1.27)
		(stroke
			(width 0)
			(type default)
		)
	)
	(bus_entry
		(at 302.26 158.75)
		(size 1.27 1.27)
		(stroke
			(width 0)
			(type default)
		)
	)
	(bus_entry
		(at 218.44 162.56)
		(size -1.27 1.27)
		(stroke
			(width 0)
			(type default)
		)
	)
	(bus_entry
		(at 199.39 87.63)
		(size -1.27 1.27)
		(stroke
			(width 0)
			(type default)
		)
	)
	(bus_entry
		(at 218.44 144.78)
		(size -1.27 1.27)
		(stroke
			(width 0)
			(type default)
		)
	)
	(bus_entry
		(at 262.89 119.38)
		(size 1.27 1.27)
		(stroke
			(width 0)
			(type default)
		)
	)
	(bus_entry
		(at 394.97 106.68)
		(size -1.27 1.27)
		(stroke
			(width 0)
			(type default)
		)
	)
	(bus_entry
		(at 262.89 93.98)
		(size 1.27 1.27)
		(stroke
			(width 0)
			(type default)
		)
	)
	(bus_entry
		(at 394.97 81.28)
		(size -1.27 1.27)
		(stroke
			(width 0)
			(type default)
		)
	)
	(bus_entry
		(at 137.16 35.56)
		(size 1.27 -1.27)
		(stroke
			(width 0)
			(type default)
		)
	)
	(bus_entry
		(at 262.89 81.28)
		(size 1.27 1.27)
		(stroke
			(width 0)
			(type default)
		)
	)
	(bus_entry
		(at 179.07 154.94)
		(size -1.27 1.27)
		(stroke
			(width 0)
			(type default)
		)
	)
	(bus_entry
		(at 218.44 165.1)
		(size -1.27 1.27)
		(stroke
			(width 0)
			(type default)
		)
	)
	(bus_entry
		(at 374.65 158.75)
		(size -1.27 1.27)
		(stroke
			(width 0)
			(type default)
		)
	)
	(bus_entry
		(at 302.26 156.21)
		(size 1.27 1.27)
		(stroke
			(width 0)
			(type default)
		)
	)
	(bus_entry
		(at 199.39 53.34)
		(size -1.27 1.27)
		(stroke
			(width 0)
			(type default)
		)
	)
	(bus_entry
		(at 218.44 104.14)
		(size -1.27 1.27)
		(stroke
			(width 0)
			(type default)
		)
	)
	(bus_entry
		(at 179.07 195.58)
		(size -1.27 1.27)
		(stroke
			(width 0)
			(type default)
		)
	)
	(bus_entry
		(at 374.65 208.28)
		(size -1.27 1.27)
		(stroke
			(width 0)
			(type default)
		)
	)
	(bus_entry
		(at 374.65 184.15)
		(size -1.27 1.27)
		(stroke
			(width 0)
			(type default)
		)
	)
	(bus_entry
		(at 179.07 146.05)
		(size -1.27 1.27)
		(stroke
			(width 0)
			(type default)
		)
	)
	(bus_entry
		(at 262.89 58.42)
		(size 1.27 1.27)
		(stroke
			(width 0)
			(type default)
		)
	)
	(bus_entry
		(at 262.89 106.68)
		(size 1.27 1.27)
		(stroke
			(width 0)
			(type default)
		)
	)
	(bus_entry
		(at 179.07 152.4)
		(size -1.27 1.27)
		(stroke
			(width 0)
			(type default)
		)
	)
	(bus_entry
		(at 262.89 71.12)
		(size 1.27 1.27)
		(stroke
			(width 0)
			(type default)
		)
	)
	(bus_entry
		(at 262.89 66.04)
		(size 1.27 1.27)
		(stroke
			(width 0)
			(type default)
		)
	)
	(bus_entry
		(at 394.97 40.64)
		(size -1.27 1.27)
		(stroke
			(width 0)
			(type default)
		)
	)
	(bus_entry
		(at 179.07 185.42)
		(size -1.27 1.27)
		(stroke
			(width 0)
			(type default)
		)
	)
	(bus_entry
		(at 218.44 157.48)
		(size -1.27 1.27)
		(stroke
			(width 0)
			(type default)
		)
	)
	(bus_entry
		(at 262.89 48.26)
		(size 1.27 1.27)
		(stroke
			(width 0)
			(type default)
		)
	)
	(bus_entry
		(at 374.65 153.67)
		(size -1.27 1.27)
		(stroke
			(width 0)
			(type default)
		)
	)
	(bus_entry
		(at 262.89 45.72)
		(size 1.27 1.27)
		(stroke
			(width 0)
			(type default)
		)
	)
	(bus_entry
		(at 218.44 173.99)
		(size -1.27 1.27)
		(stroke
			(width 0)
			(type default)
		)
	)
	(bus_entry
		(at 218.44 198.12)
		(size -1.27 1.27)
		(stroke
			(width 0)
			(type default)
		)
	)
	(bus_entry
		(at 218.44 195.58)
		(size -1.27 1.27)
		(stroke
			(width 0)
			(type default)
		)
	)
	(bus_entry
		(at 374.65 189.23)
		(size -1.27 1.27)
		(stroke
			(width 0)
			(type default)
		)
	)
	(bus_entry
		(at 302.26 184.15)
		(size 1.27 1.27)
		(stroke
			(width 0)
			(type default)
		)
	)
	(bus_entry
		(at 218.44 191.77)
		(size -1.27 1.27)
		(stroke
			(width 0)
			(type default)
		)
	)
	(bus_entry
		(at 262.89 129.54)
		(size 1.27 1.27)
		(stroke
			(width 0)
			(type default)
		)
	)
	(bus_entry
		(at 179.07 161.29)
		(size -1.27 1.27)
		(stroke
			(width 0)
			(type default)
		)
	)
	(bus_entry
		(at 302.26 194.31)
		(size 1.27 1.27)
		(stroke
			(width 0)
			(type default)
		)
	)
	(bus_entry
		(at 374.65 156.21)
		(size -1.27 1.27)
		(stroke
			(width 0)
			(type default)
		)
	)
	(bus_entry
		(at 302.26 186.69)
		(size 1.27 1.27)
		(stroke
			(width 0)
			(type default)
		)
	)
	(bus_entry
		(at 262.89 91.44)
		(size 1.27 1.27)
		(stroke
			(width 0)
			(type default)
		)
	)
	(bus_entry
		(at 302.26 203.2)
		(size 1.27 1.27)
		(stroke
			(width 0)
			(type default)
		)
	)
	(bus_entry
		(at 302.26 191.77)
		(size 1.27 1.27)
		(stroke
			(width 0)
			(type default)
		)
	)
	(bus_entry
		(at 302.26 153.67)
		(size 1.27 1.27)
		(stroke
			(width 0)
			(type default)
		)
	)
	(bus_entry
		(at 262.89 104.14)
		(size 1.27 1.27)
		(stroke
			(width 0)
			(type default)
		)
	)
	(bus_entry
		(at 218.44 160.02)
		(size -1.27 1.27)
		(stroke
			(width 0)
			(type default)
		)
	)
	(bus_entry
		(at 374.65 148.59)
		(size -1.27 1.27)
		(stroke
			(width 0)
			(type default)
		)
	)
	(bus_entry
		(at 374.65 172.72)
		(size -1.27 1.27)
		(stroke
			(width 0)
			(type default)
		)
	)
	(bus_entry
		(at 262.89 101.6)
		(size 1.27 1.27)
		(stroke
			(width 0)
			(type default)
		)
	)
	(bus_entry
		(at 394.97 134.62)
		(size -1.27 1.27)
		(stroke
			(width 0)
			(type default)
		)
	)
	(bus_entry
		(at 262.89 83.82)
		(size 1.27 1.27)
		(stroke
			(width 0)
			(type default)
		)
	)
	(bus_entry
		(at 218.44 106.68)
		(size -1.27 1.27)
		(stroke
			(width 0)
			(type default)
		)
	)
	(bus_entry
		(at 218.44 189.23)
		(size -1.27 1.27)
		(stroke
			(width 0)
			(type default)
		)
	)
	(bus_entry
		(at 374.65 205.74)
		(size -1.27 1.27)
		(stroke
			(width 0)
			(type default)
		)
	)
	(bus_entry
		(at 302.26 181.61)
		(size 1.27 1.27)
		(stroke
			(width 0)
			(type default)
		)
	)
	(bus_entry
		(at 68.58 35.56)
		(size -1.27 -1.27)
		(stroke
			(width 0)
			(type default)
		)
	)
	(bus_entry
		(at 302.26 170.18)
		(size 1.27 1.27)
		(stroke
			(width 0)
			(type default)
		)
	)
	(bus_entry
		(at 179.07 125.73)
		(size -1.27 1.27)
		(stroke
			(width 0)
			(type default)
		)
	)
	(bus_entry
		(at 218.44 147.32)
		(size -1.27 1.27)
		(stroke
			(width 0)
			(type default)
		)
	)
	(bus_entry
		(at 262.89 132.08)
		(size 1.27 1.27)
		(stroke
			(width 0)
			(type default)
		)
	)
	(bus_entry
		(at 302.26 161.29)
		(size 1.27 1.27)
		(stroke
			(width 0)
			(type default)
		)
	)
	(bus_entry
		(at 179.07 113.03)
		(size -1.27 1.27)
		(stroke
			(width 0)
			(type default)
		)
	)
	(bus_entry
		(at 302.26 177.8)
		(size 1.27 1.27)
		(stroke
			(width 0)
			(type default)
		)
	)
	(bus_entry
		(at 137.16 39.37)
		(size 1.27 -1.27)
		(stroke
			(width 0)
			(type default)
		)
	)
	(bus_entry
		(at 394.97 58.42)
		(size -1.27 1.27)
		(stroke
			(width 0)
			(type default)
		)
	)
	(bus_entry
		(at 262.89 55.88)
		(size 1.27 1.27)
		(stroke
			(width 0)
			(type default)
		)
	)
	(bus_entry
		(at 262.89 68.58)
		(size 1.27 1.27)
		(stroke
			(width 0)
			(type default)
		)
	)
	(bus_entry
		(at 199.39 90.17)
		(size -1.27 1.27)
		(stroke
			(width 0)
			(type default)
		)
	)
	(bus_entry
		(at 262.89 53.34)
		(size 1.27 1.27)
		(stroke
			(width 0)
			(type default)
		)
	)
	(bus_entry
		(at 374.65 161.29)
		(size -1.27 1.27)
		(stroke
			(width 0)
			(type default)
		)
	)
	(bus_entry
		(at 374.65 186.69)
		(size -1.27 1.27)
		(stroke
			(width 0)
			(type default)
		)
	)
	(bus_entry
		(at 218.44 110.49)
		(size -1.27 1.27)
		(stroke
			(width 0)
			(type default)
		)
	)
	(bus_entry
		(at 302.26 175.26)
		(size 1.27 1.27)
		(stroke
			(width 0)
			(type default)
		)
	)
	(bus_entry
		(at 218.44 171.45)
		(size -1.27 1.27)
		(stroke
			(width 0)
			(type default)
		)
	)
	(bus_entry
		(at 179.07 173.99)
		(size -1.27 1.27)
		(stroke
			(width 0)
			(type default)
		)
	)
	(bus_entry
		(at 137.16 33.02)
		(size 1.27 -1.27)
		(stroke
			(width 0)
			(type default)
		)
	)
	(bus_entry
		(at 179.07 158.75)
		(size -1.27 1.27)
		(stroke
			(width 0)
			(type default)
		)
	)
	(bus_entry
		(at 262.89 43.18)
		(size 1.27 1.27)
		(stroke
			(width 0)
			(type default)
		)
	)
	(bus_entry
		(at 262.89 50.8)
		(size 1.27 1.27)
		(stroke
			(width 0)
			(type default)
		)
	)
	(bus_entry
		(at 179.07 163.83)
		(size -1.27 1.27)
		(stroke
			(width 0)
			(type default)
		)
	)
	(bus_entry
		(at 68.58 39.37)
		(size -1.27 -1.27)
		(stroke
			(width 0)
			(type default)
		)
	)
	(bus_entry
		(at 262.89 96.52)
		(size 1.27 1.27)
		(stroke
			(width 0)
			(type default)
		)
	)
	(bus_entry
		(at 68.58 33.02)
		(size -1.27 -1.27)
		(stroke
			(width 0)
			(type default)
		)
	)
	(bus_entry
		(at 179.07 148.59)
		(size -1.27 1.27)
		(stroke
			(width 0)
			(type default)
		)
	)
	(bus_entry
		(at 262.89 109.22)
		(size 1.27 1.27)
		(stroke
			(width 0)
			(type default)
		)
	)
	(bus_entry
		(at 218.44 123.19)
		(size -1.27 1.27)
		(stroke
			(width 0)
			(type default)
		)
	)
	(bus_entry
		(at 179.07 106.68)
		(size -1.27 1.27)
		(stroke
			(width 0)
			(type default)
		)
	)
	(bus_entry
		(at 179.07 190.5)
		(size -1.27 1.27)
		(stroke
			(width 0)
			(type default)
		)
	)
	(bus_entry
		(at 302.26 210.82)
		(size 1.27 1.27)
		(stroke
			(width 0)
			(type default)
		)
	)
	(bus_entry
		(at 218.44 125.73)
		(size -1.27 1.27)
		(stroke
			(width 0)
			(type default)
		)
	)
	(bus_entry
		(at 179.07 171.45)
		(size -1.27 1.27)
		(stroke
			(width 0)
			(type default)
		)
	)
	(bus_entry
		(at 218.44 153.67)
		(size -1.27 1.27)
		(stroke
			(width 0)
			(type default)
		)
	)
	(bus_entry
		(at 179.07 119.38)
		(size -1.27 1.27)
		(stroke
			(width 0)
			(type default)
		)
	)
	(bus_entry
		(at 394.97 83.82)
		(size -1.27 1.27)
		(stroke
			(width 0)
			(type default)
		)
	)
	(bus_entry
		(at 374.65 181.61)
		(size -1.27 1.27)
		(stroke
			(width 0)
			(type default)
		)
	)
	(bus_entry
		(at 179.07 168.91)
		(size -1.27 1.27)
		(stroke
			(width 0)
			(type default)
		)
	)
	(bus_entry
		(at 394.97 55.88)
		(size -1.27 1.27)
		(stroke
			(width 0)
			(type default)
		)
	)
	(bus_entry
		(at 302.26 172.72)
		(size 1.27 1.27)
		(stroke
			(width 0)
			(type default)
		)
	)
	(bus_entry
		(at 179.07 182.88)
		(size -1.27 1.27)
		(stroke
			(width 0)
			(type default)
		)
	)
	(bus_entry
		(at 302.26 148.59)
		(size 1.27 1.27)
		(stroke
			(width 0)
			(type default)
		)
	)
	(bus_entry
		(at 374.65 191.77)
		(size -1.27 1.27)
		(stroke
			(width 0)
			(type default)
		)
	)
	(bus_entry
		(at 374.65 151.13)
		(size -1.27 1.27)
		(stroke
			(width 0)
			(type default)
		)
	)
	(bus_entry
		(at 179.07 198.12)
		(size -1.27 1.27)
		(stroke
			(width 0)
			(type default)
		)
	)
	(wire
		(pts
			(xy 161.29 105.41) (xy 177.8 105.41)
		)
		(stroke
			(width 0)
			(type default)
		)
	)
	(wire
		(pts
			(xy 64.77 163.83) (xy 81.28 163.83)
		)
		(stroke
			(width 0)
			(type default)
		)
	)
	(bus
		(pts
			(xy 302.26 156.21) (xy 302.26 158.75)
		)
		(stroke
			(width 0)
			(type default)
		)
	)
	(wire
		(pts
			(xy 101.6 233.68) (xy 115.57 233.68)
		)
		(stroke
			(width 0)
			(type default)
		)
	)
	(wire
		(pts
			(xy 52.07 82.55) (xy 60.96 82.55)
		)
		(stroke
			(width 0)
			(type default)
		)
	)
	(wire
		(pts
			(xy 125.73 33.02) (xy 137.16 33.02)
		)
		(stroke
			(width 0)
			(type default)
		)
	)
	(bus
		(pts
			(xy 220.98 102.87) (xy 219.71 102.87)
		)
		(stroke
			(width 0)
			(type default)
		)
	)
	(wire
		(pts
			(xy 303.53 187.96) (xy 321.31 187.96)
		)
		(stroke
			(width 0)
			(type default)
		)
	)
	(bus
		(pts
			(xy 262.89 91.44) (xy 261.62 90.17)
		)
		(stroke
			(width 0)
			(type default)
		)
	)
	(wire
		(pts
			(xy 181.61 58.42) (xy 198.12 58.42)
		)
		(stroke
			(width 0)
			(type default)
		)
	)
	(wire
		(pts
			(xy 264.16 54.61) (xy 287.02 54.61)
		)
		(stroke
			(width 0)
			(type default)
		)
	)
	(wire
		(pts
			(xy 303.53 171.45) (xy 321.31 171.45)
		)
		(stroke
			(width 0)
			(type default)
		)
	)
	(wire
		(pts
			(xy 350.52 110.49) (xy 373.38 110.49)
		)
		(stroke
			(width 0)
			(type default)
		)
	)
	(bus
		(pts
			(xy 374.65 148.59) (xy 374.65 151.13)
		)
		(stroke
			(width 0)
			(type default)
		)
	)
	(bus
		(pts
			(xy 218.44 189.23) (xy 218.44 191.77)
		)
		(stroke
			(width 0)
			(type default)
		)
	)
	(wire
		(pts
			(xy 115.57 224.79) (xy 115.57 226.06)
		)
		(stroke
			(width 0)
			(type default)
		)
	)
	(wire
		(pts
			(xy 264.16 67.31) (xy 279.4 67.31)
		)
		(stroke
			(width 0)
			(type default)
		)
	)
	(bus
		(pts
			(xy 302.26 194.31) (xy 302.26 203.2)
		)
		(stroke
			(width 0)
			(type default)
		)
	)
	(bus
		(pts
			(xy 302.26 148.59) (xy 300.99 147.32)
		)
		(stroke
			(width 0)
			(type default)
		)
	)
	(wire
		(pts
			(xy 200.66 170.18) (xy 217.17 170.18)
		)
		(stroke
			(width 0)
			(type default)
		)
	)
	(bus
		(pts
			(xy 375.92 180.34) (xy 381 180.34)
		)
		(stroke
			(width 0)
			(type default)
		)
	)
	(wire
		(pts
			(xy 262.89 237.49) (xy 266.7 237.49)
		)
		(stroke
			(width 0)
			(type default)
		)
	)
	(wire
		(pts
			(xy 64.77 143.51) (xy 81.28 143.51)
		)
		(stroke
			(width 0)
			(type default)
		)
	)
	(wire
		(pts
			(xy 181.61 82.55) (xy 198.12 82.55)
		)
		(stroke
			(width 0)
			(type default)
		)
	)
	(wire
		(pts
			(xy 292.1 44.45) (xy 307.34 44.45)
		)
		(stroke
			(width 0)
			(type default)
		)
	)
	(wire
		(pts
			(xy 200.66 177.8) (xy 217.17 177.8)
		)
		(stroke
			(width 0)
			(type default)
		)
	)
	(wire
		(pts
			(xy 292.1 135.89) (xy 307.34 135.89)
		)
		(stroke
			(width 0)
			(type default)
		)
	)
	(bus
		(pts
			(xy 394.97 132.08) (xy 394.97 134.62)
		)
		(stroke
			(width 0)
			(type default)
		)
	)
	(wire
		(pts
			(xy 200.66 158.75) (xy 217.17 158.75)
		)
		(stroke
			(width 0)
			(type default)
		)
	)
	(bus
		(pts
			(xy 200.66 64.77) (xy 199.39 66.04)
		)
		(stroke
			(width 0)
			(type default)
		)
	)
	(bus
		(pts
			(xy 223.52 143.51) (xy 219.71 143.51)
		)
		(stroke
			(width 0)
			(type default)
		)
	)
	(bus
		(pts
			(xy 199.39 87.63) (xy 199.39 90.17)
		)
		(stroke
			(width 0)
			(type default)
		)
	)
	(bus
		(pts
			(xy 262.89 40.64) (xy 261.62 39.37)
		)
		(stroke
			(width 0)
			(type default)
		)
	)
	(wire
		(pts
			(xy 64.77 123.19) (xy 81.28 123.19)
		)
		(stroke
			(width 0)
			(type default)
		)
	)
	(bus
		(pts
			(xy 262.89 93.98) (xy 262.89 96.52)
		)
		(stroke
			(width 0)
			(type default)
		)
	)
	(bus
		(pts
			(xy 260.35 64.77) (xy 261.62 64.77)
		)
		(stroke
			(width 0)
			(type default)
		)
	)
	(wire
		(pts
			(xy 264.16 118.11) (xy 279.4 118.11)
		)
		(stroke
			(width 0)
			(type default)
		)
	)
	(wire
		(pts
			(xy 292.1 59.69) (xy 307.34 59.69)
		)
		(stroke
			(width 0)
			(type default)
		)
	)
	(bus
		(pts
			(xy 262.89 119.38) (xy 262.89 121.92)
		)
		(stroke
			(width 0)
			(type default)
		)
	)
	(wire
		(pts
			(xy 64.77 107.95) (xy 81.28 107.95)
		)
		(stroke
			(width 0)
			(type default)
		)
	)
	(wire
		(pts
			(xy 284.48 82.55) (xy 307.34 82.55)
		)
		(stroke
			(width 0)
			(type default)
		)
	)
	(bus
		(pts
			(xy 179.07 146.05) (xy 179.07 148.59)
		)
		(stroke
			(width 0)
			(type default)
		)
	)
	(wire
		(pts
			(xy 200.66 172.72) (xy 217.17 172.72)
		)
		(stroke
			(width 0)
			(type default)
		)
	)
	(wire
		(pts
			(xy 125.73 39.37) (xy 137.16 39.37)
		)
		(stroke
			(width 0)
			(type default)
		)
	)
	(wire
		(pts
			(xy 355.6 190.5) (xy 373.38 190.5)
		)
		(stroke
			(width 0)
			(type default)
		)
	)
	(wire
		(pts
			(xy 222.25 269.24) (xy 222.25 267.97)
		)
		(stroke
			(width 0)
			(type default)
		)
	)
	(wire
		(pts
			(xy 284.48 107.95) (xy 307.34 107.95)
		)
		(stroke
			(width 0)
			(type default)
		)
	)
	(wire
		(pts
			(xy 200.66 199.39) (xy 217.17 199.39)
		)
		(stroke
			(width 0)
			(type default)
		)
	)
	(wire
		(pts
			(xy 63.5 82.55) (xy 78.74 82.55)
		)
		(stroke
			(width 0)
			(type default)
		)
	)
	(wire
		(pts
			(xy 266.7 237.49) (xy 290.83 237.49)
		)
		(stroke
			(width 0)
			(type default)
		)
	)
	(wire
		(pts
			(xy 66.04 223.52) (xy 66.04 224.79)
		)
		(stroke
			(width 0)
			(type default)
		)
	)
	(bus
		(pts
			(xy 262.89 76.2) (xy 262.89 78.74)
		)
		(stroke
			(width 0)
			(type default)
		)
	)
	(wire
		(pts
			(xy 74.93 233.68) (xy 74.93 223.52)
		)
		(stroke
			(width 0)
			(type default)
		)
	)
	(bus
		(pts
			(xy 397.51 90.17) (xy 396.24 90.17)
		)
		(stroke
			(width 0)
			(type default)
		)
	)
	(wire
		(pts
			(xy 205.74 234.95) (xy 209.55 234.95)
		)
		(stroke
			(width 0)
			(type default)
		)
	)
	(wire
		(pts
			(xy 107.95 241.3) (xy 93.98 241.3)
		)
		(stroke
			(width 0)
			(type default)
		)
	)
	(wire
		(pts
			(xy 96.52 248.92) (xy 93.98 248.92)
		)
		(stroke
			(width 0)
			(type default)
		)
	)
	(wire
		(pts
			(xy 138.43 115.57) (xy 121.92 115.57)
		)
		(stroke
			(width 0)
			(type default)
		)
	)
	(bus
		(pts
			(xy 374.65 186.69) (xy 374.65 189.23)
		)
		(stroke
			(width 0)
			(type default)
		)
	)
	(wire
		(pts
			(xy 222.25 241.3) (xy 222.25 240.03)
		)
		(stroke
			(width 0)
			(type default)
		)
	)
	(wire
		(pts
			(xy 64.77 110.49) (xy 81.28 110.49)
		)
		(stroke
			(width 0)
			(type default)
		)
	)
	(wire
		(pts
			(xy 181.61 67.31) (xy 198.12 67.31)
		)
		(stroke
			(width 0)
			(type default)
		)
	)
	(wire
		(pts
			(xy 264.16 107.95) (xy 279.4 107.95)
		)
		(stroke
			(width 0)
			(type default)
		)
	)
	(wire
		(pts
			(xy 68.58 33.02) (xy 78.74 33.02)
		)
		(stroke
			(width 0)
			(type default)
		)
	)
	(bus
		(pts
			(xy 218.44 160.02) (xy 218.44 162.56)
		)
		(stroke
			(width 0)
			(type default)
		)
	)
	(wire
		(pts
			(xy 64.77 168.91) (xy 81.28 168.91)
		)
		(stroke
			(width 0)
			(type default)
		)
	)
	(wire
		(pts
			(xy 303.53 212.09) (xy 321.31 212.09)
		)
		(stroke
			(width 0)
			(type default)
		)
	)
	(wire
		(pts
			(xy 125.73 82.55) (xy 130.81 82.55)
		)
		(stroke
			(width 0)
			(type default)
		)
	)
	(bus
		(pts
			(xy 199.39 66.04) (xy 199.39 68.58)
		)
		(stroke
			(width 0)
			(type default)
		)
	)
	(wire
		(pts
			(xy 121.92 138.43) (xy 138.43 138.43)
		)
		(stroke
			(width 0)
			(type default)
		)
	)
	(bus
		(pts
			(xy 394.97 116.84) (xy 396.24 115.57)
		)
		(stroke
			(width 0)
			(type default)
		)
	)
	(wire
		(pts
			(xy 161.29 194.31) (xy 177.8 194.31)
		)
		(stroke
			(width 0)
			(type default)
		)
	)
	(bus
		(pts
			(xy 262.89 66.04) (xy 261.62 64.77)
		)
		(stroke
			(width 0)
			(type default)
		)
	)
	(bus
		(pts
			(xy 374.65 205.74) (xy 374.65 208.28)
		)
		(stroke
			(width 0)
			(type default)
		)
	)
	(bus
		(pts
			(xy 179.07 106.68) (xy 179.07 110.49)
		)
		(stroke
			(width 0)
			(type default)
		)
	)
	(wire
		(pts
			(xy 125.73 58.42) (xy 143.51 58.42)
		)
		(stroke
			(width 0)
			(type default)
		)
	)
	(bus
		(pts
			(xy 262.89 43.18) (xy 262.89 45.72)
		)
		(stroke
			(width 0)
			(type default)
		)
	)
	(bus
		(pts
			(xy 374.65 181.61) (xy 374.65 184.15)
		)
		(stroke
			(width 0)
			(type default)
		)
	)
	(bus
		(pts
			(xy 67.31 34.29) (xy 67.31 31.75)
		)
		(stroke
			(width 0)
			(type default)
		)
	)
	(wire
		(pts
			(xy 137.16 273.05) (xy 142.24 273.05)
		)
		(stroke
			(width 0)
			(type default)
		)
	)
	(bus
		(pts
			(xy 394.97 40.64) (xy 394.97 55.88)
		)
		(stroke
			(width 0)
			(type default)
		)
	)
	(bus
		(pts
			(xy 302.26 153.67) (xy 302.26 156.21)
		)
		(stroke
			(width 0)
			(type default)
		)
	)
	(wire
		(pts
			(xy 292.1 95.25) (xy 307.34 95.25)
		)
		(stroke
			(width 0)
			(type default)
		)
	)
	(bus
		(pts
			(xy 179.07 173.99) (xy 179.07 176.53)
		)
		(stroke
			(width 0)
			(type default)
		)
	)
	(bus
		(pts
			(xy 218.44 123.19) (xy 218.44 125.73)
		)
		(stroke
			(width 0)
			(type default)
		)
	)
	(wire
		(pts
			(xy 168.91 236.22) (xy 170.18 236.22)
		)
		(stroke
			(width 0)
			(type default)
		)
	)
	(wire
		(pts
			(xy 69.85 255.27) (xy 62.23 255.27)
		)
		(stroke
			(width 0)
			(type default)
		)
	)
	(bus
		(pts
			(xy 394.97 66.04) (xy 396.24 64.77)
		)
		(stroke
			(width 0)
			(type default)
		)
	)
	(wire
		(pts
			(xy 115.57 231.14) (xy 115.57 233.68)
		)
		(stroke
			(width 0)
			(type default)
		)
	)
	(wire
		(pts
			(xy 303.53 176.53) (xy 321.31 176.53)
		)
		(stroke
			(width 0)
			(type default)
		)
	)
	(wire
		(pts
			(xy 138.43 118.11) (xy 121.92 118.11)
		)
		(stroke
			(width 0)
			(type default)
		)
	)
	(bus
		(pts
			(xy 139.7 30.48) (xy 138.43 31.75)
		)
		(stroke
			(width 0)
			(type default)
		)
	)
	(bus
		(pts
			(xy 201.93 80.01) (xy 200.66 80.01)
		)
		(stroke
			(width 0)
			(type default)
		)
	)
	(wire
		(pts
			(xy 181.61 85.09) (xy 198.12 85.09)
		)
		(stroke
			(width 0)
			(type default)
		)
	)
	(wire
		(pts
			(xy 209.55 265.43) (xy 213.36 265.43)
		)
		(stroke
			(width 0)
			(type default)
		)
	)
	(bus
		(pts
			(xy 262.89 116.84) (xy 261.62 115.57)
		)
		(stroke
			(width 0)
			(type default)
		)
	)
	(bus
		(pts
			(xy 262.89 127) (xy 262.89 129.54)
		)
		(stroke
			(width 0)
			(type default)
		)
	)
	(wire
		(pts
			(xy 355.6 204.47) (xy 373.38 204.47)
		)
		(stroke
			(width 0)
			(type default)
		)
	)
	(wire
		(pts
			(xy 209.55 237.49) (xy 213.36 237.49)
		)
		(stroke
			(width 0)
			(type default)
		)
	)
	(wire
		(pts
			(xy 63.5 62.23) (xy 74.93 62.23)
		)
		(stroke
			(width 0)
			(type default)
		)
	)
	(wire
		(pts
			(xy 264.16 57.15) (xy 279.4 57.15)
		)
		(stroke
			(width 0)
			(type default)
		)
	)
	(wire
		(pts
			(xy 284.48 123.19) (xy 307.34 123.19)
		)
		(stroke
			(width 0)
			(type default)
		)
	)
	(wire
		(pts
			(xy 52.07 74.93) (xy 59.69 74.93)
		)
		(stroke
			(width 0)
			(type default)
		)
	)
	(wire
		(pts
			(xy 161.29 156.21) (xy 177.8 156.21)
		)
		(stroke
			(width 0)
			(type default)
		)
	)
	(wire
		(pts
			(xy 116.84 261.62) (xy 116.84 262.89)
		)
		(stroke
			(width 0)
			(type default)
		)
	)
	(wire
		(pts
			(xy 378.46 135.89) (xy 393.7 135.89)
		)
		(stroke
			(width 0)
			(type default)
		)
	)
	(wire
		(pts
			(xy 181.61 88.9) (xy 198.12 88.9)
		)
		(stroke
			(width 0)
			(type default)
		)
	)
	(wire
		(pts
			(xy 264.16 77.47) (xy 279.4 77.47)
		)
		(stroke
			(width 0)
			(type default)
		)
	)
	(bus
		(pts
			(xy 302.26 175.26) (xy 302.26 177.8)
		)
		(stroke
			(width 0)
			(type default)
		)
	)
	(bus
		(pts
			(xy 218.44 119.38) (xy 218.44 123.19)
		)
		(stroke
			(width 0)
			(type default)
		)
	)
	(bus
		(pts
			(xy 181.61 144.78) (xy 180.34 144.78)
		)
		(stroke
			(width 0)
			(type default)
		)
	)
	(bus
		(pts
			(xy 262.89 55.88) (xy 262.89 58.42)
		)
		(stroke
			(width 0)
			(type default)
		)
	)
	(wire
		(pts
			(xy 242.57 237.49) (xy 257.81 237.49)
		)
		(stroke
			(width 0)
			(type default)
		)
	)
	(wire
		(pts
			(xy 303.53 182.88) (xy 321.31 182.88)
		)
		(stroke
			(width 0)
			(type default)
		)
	)
	(wire
		(pts
			(xy 266.7 237.49) (xy 266.7 240.03)
		)
		(stroke
			(width 0)
			(type default)
		)
	)
	(wire
		(pts
			(xy 63.5 67.31) (xy 78.74 67.31)
		)
		(stroke
			(width 0)
			(type default)
		)
	)
	(wire
		(pts
			(xy 184.15 243.84) (xy 168.91 243.84)
		)
		(stroke
			(width 0)
			(type default)
		)
	)
	(wire
		(pts
			(xy 370.84 133.35) (xy 393.7 133.35)
		)
		(stroke
			(width 0)
			(type default)
		)
	)
	(wire
		(pts
			(xy 200.66 105.41) (xy 217.17 105.41)
		)
		(stroke
			(width 0)
			(type default)
		)
	)
	(wire
		(pts
			(xy 350.52 57.15) (xy 365.76 57.15)
		)
		(stroke
			(width 0)
			(type default)
		)
	)
	(bus
		(pts
			(xy 302.26 205.74) (xy 302.26 208.28)
		)
		(stroke
			(width 0)
			(type default)
		)
	)
	(bus
		(pts
			(xy 302.26 161.29) (xy 302.26 170.18)
		)
		(stroke
			(width 0)
			(type default)
		)
	)
	(wire
		(pts
			(xy 284.48 118.11) (xy 307.34 118.11)
		)
		(stroke
			(width 0)
			(type default)
		)
	)
	(bus
		(pts
			(xy 199.39 83.82) (xy 199.39 87.63)
		)
		(stroke
			(width 0)
			(type default)
		)
	)
	(bus
		(pts
			(xy 302.26 203.2) (xy 302.26 205.74)
		)
		(stroke
			(width 0)
			(type default)
		)
	)
	(wire
		(pts
			(xy 161.29 149.86) (xy 177.8 149.86)
		)
		(stroke
			(width 0)
			(type default)
		)
	)
	(wire
		(pts
			(xy 200.66 114.3) (xy 217.17 114.3)
		)
		(stroke
			(width 0)
			(type default)
		)
	)
	(wire
		(pts
			(xy 303.53 162.56) (xy 321.31 162.56)
		)
		(stroke
			(width 0)
			(type default)
		)
	)
	(wire
		(pts
			(xy 284.48 46.99) (xy 307.34 46.99)
		)
		(stroke
			(width 0)
			(type default)
		)
	)
	(wire
		(pts
			(xy 64.77 140.97) (xy 81.28 140.97)
		)
		(stroke
			(width 0)
			(type default)
		)
	)
	(polyline
		(pts
			(xy 191.77 208.915) (xy 191.77 284.48)
		)
		(stroke
			(width 0)
			(type default)
		)
	)
	(wire
		(pts
			(xy 274.32 234.95) (xy 290.83 234.95)
		)
		(stroke
			(width 0)
			(type default)
		)
	)
	(wire
		(pts
			(xy 373.38 171.45) (xy 355.6 171.45)
		)
		(stroke
			(width 0)
			(type default)
		)
	)
	(bus
		(pts
			(xy 302.26 158.75) (xy 302.26 161.29)
		)
		(stroke
			(width 0)
			(type default)
		)
	)
	(wire
		(pts
			(xy 57.15 243.84) (xy 43.18 243.84)
		)
		(stroke
			(width 0)
			(type default)
		)
	)
	(wire
		(pts
			(xy 200.66 120.65) (xy 217.17 120.65)
		)
		(stroke
			(width 0)
			(type default)
		)
	)
	(wire
		(pts
			(xy 370.84 57.15) (xy 393.7 57.15)
		)
		(stroke
			(width 0)
			(type default)
		)
	)
	(wire
		(pts
			(xy 124.46 264.16) (xy 130.81 264.16)
		)
		(stroke
			(width 0)
			(type default)
		)
	)
	(wire
		(pts
			(xy 64.77 105.41) (xy 81.28 105.41)
		)
		(stroke
			(width 0)
			(type default)
		)
	)
	(wire
		(pts
			(xy 264.16 69.85) (xy 287.02 69.85)
		)
		(stroke
			(width 0)
			(type default)
		)
	)
	(wire
		(pts
			(xy 218.44 237.49) (xy 223.52 237.49)
		)
		(stroke
			(width 0)
			(type default)
		)
	)
	(wire
		(pts
			(xy 177.8 170.18) (xy 161.29 170.18)
		)
		(stroke
			(width 0)
			(type default)
		)
	)
	(bus
		(pts
			(xy 179.07 163.83) (xy 179.07 166.37)
		)
		(stroke
			(width 0)
			(type default)
		)
	)
	(polyline
		(pts
			(xy 299.72 252.73) (xy 299.72 208.915)
		)
		(stroke
			(width 0)
			(type default)
		)
	)
	(bus
		(pts
			(xy 199.39 50.8) (xy 199.39 53.34)
		)
		(stroke
			(width 0)
			(type default)
		)
	)
	(wire
		(pts
			(xy 177.8 160.02) (xy 161.29 160.02)
		)
		(stroke
			(width 0)
			(type default)
		)
	)
	(bus
		(pts
			(xy 397.51 115.57) (xy 396.24 115.57)
		)
		(stroke
			(width 0)
			(type default)
		)
	)
	(wire
		(pts
			(xy 355.6 182.88) (xy 373.38 182.88)
		)
		(stroke
			(width 0)
			(type default)
		)
	)
	(bus
		(pts
			(xy 374.65 172.72) (xy 374.65 175.26)
		)
		(stroke
			(width 0)
			(type default)
		)
	)
	(bus
		(pts
			(xy 218.44 147.32) (xy 218.44 151.13)
		)
		(stroke
			(width 0)
			(type default)
		)
	)
	(wire
		(pts
			(xy 77.47 62.23) (xy 78.74 62.23)
		)
		(stroke
			(width 0)
			(type default)
		)
	)
	(bus
		(pts
			(xy 374.65 151.13) (xy 374.65 153.67)
		)
		(stroke
			(width 0)
			(type default)
		)
	)
	(wire
		(pts
			(xy 138.43 110.49) (xy 121.92 110.49)
		)
		(stroke
			(width 0)
			(type default)
		)
	)
	(wire
		(pts
			(xy 60.96 82.55) (xy 60.96 77.47)
		)
		(stroke
			(width 0)
			(type default)
		)
	)
	(wire
		(pts
			(xy 26.67 74.93) (xy 46.99 74.93)
		)
		(stroke
			(width 0)
			(type default)
		)
	)
	(wire
		(pts
			(xy 264.16 97.79) (xy 279.4 97.79)
		)
		(stroke
			(width 0)
			(type default)
		)
	)
	(bus
		(pts
			(xy 394.97 40.64) (xy 396.24 39.37)
		)
		(stroke
			(width 0)
			(type default)
		)
	)
	(bus
		(pts
			(xy 179.07 168.91) (xy 179.07 171.45)
		)
		(stroke
			(width 0)
			(type default)
		)
	)
	(wire
		(pts
			(xy 97.79 262.89) (xy 116.84 262.89)
		)
		(stroke
			(width 0)
			(type default)
		)
	)
	(wire
		(pts
			(xy 378.46 59.69) (xy 393.7 59.69)
		)
		(stroke
			(width 0)
			(type default)
		)
	)
	(wire
		(pts
			(xy 350.52 133.35) (xy 365.76 133.35)
		)
		(stroke
			(width 0)
			(type default)
		)
	)
	(bus
		(pts
			(xy 262.89 132.08) (xy 262.89 134.62)
		)
		(stroke
			(width 0)
			(type default)
		)
	)
	(wire
		(pts
			(xy 63.5 69.85) (xy 78.74 69.85)
		)
		(stroke
			(width 0)
			(type default)
		)
	)
	(wire
		(pts
			(xy 284.48 57.15) (xy 307.34 57.15)
		)
		(stroke
			(width 0)
			(type default)
		)
	)
	(wire
		(pts
			(xy 177.8 165.1) (xy 161.29 165.1)
		)
		(stroke
			(width 0)
			(type default)
		)
	)
	(bus
		(pts
			(xy 218.44 144.78) (xy 219.71 143.51)
		)
		(stroke
			(width 0)
			(type default)
		)
	)
	(wire
		(pts
			(xy 76.2 241.3) (xy 62.23 241.3)
		)
		(stroke
			(width 0)
			(type default)
		)
	)
	(wire
		(pts
			(xy 222.25 240.03) (xy 223.52 240.03)
		)
		(stroke
			(width 0)
			(type default)
		)
	)
	(wire
		(pts
			(xy 177.8 175.26) (xy 161.29 175.26)
		)
		(stroke
			(width 0)
			(type default)
		)
	)
	(bus
		(pts
			(xy 181.61 102.87) (xy 180.34 102.87)
		)
		(stroke
			(width 0)
			(type default)
		)
	)
	(wire
		(pts
			(xy 64.77 128.27) (xy 81.28 128.27)
		)
		(stroke
			(width 0)
			(type default)
		)
	)
	(bus
		(pts
			(xy 222.25 187.96) (xy 219.71 187.96)
		)
		(stroke
			(width 0)
			(type default)
		)
	)
	(wire
		(pts
			(xy 264.16 100.33) (xy 287.02 100.33)
		)
		(stroke
			(width 0)
			(type default)
		)
	)
	(wire
		(pts
			(xy 303.53 207.01) (xy 321.31 207.01)
		)
		(stroke
			(width 0)
			(type default)
		)
	)
	(wire
		(pts
			(xy 264.16 49.53) (xy 287.02 49.53)
		)
		(stroke
			(width 0)
			(type default)
		)
	)
	(wire
		(pts
			(xy 142.24 273.05) (xy 161.29 273.05)
		)
		(stroke
			(width 0)
			(type default)
		)
	)
	(bus
		(pts
			(xy 394.97 91.44) (xy 394.97 106.68)
		)
		(stroke
			(width 0)
			(type default)
		)
	)
	(wire
		(pts
			(xy 130.81 275.59) (xy 130.81 278.13)
		)
		(stroke
			(width 0)
			(type default)
		)
	)
	(bus
		(pts
			(xy 262.89 106.68) (xy 262.89 109.22)
		)
		(stroke
			(width 0)
			(type default)
		)
	)
	(bus
		(pts
			(xy 138.43 40.64) (xy 138.43 38.1)
		)
		(stroke
			(width 0)
			(type default)
		)
	)
	(bus
		(pts
			(xy 179.07 158.75) (xy 179.07 161.29)
		)
		(stroke
			(width 0)
			(type default)
		)
	)
	(bus
		(pts
			(xy 179.07 180.34) (xy 179.07 182.88)
		)
		(stroke
			(width 0)
			(type default)
		)
	)
	(bus
		(pts
			(xy 218.44 113.03) (xy 218.44 116.84)
		)
		(stroke
			(width 0)
			(type default)
		)
	)
	(wire
		(pts
			(xy 125.73 68.58) (xy 143.51 68.58)
		)
		(stroke
			(width 0)
			(type default)
		)
	)
	(wire
		(pts
			(xy 292.1 49.53) (xy 307.34 49.53)
		)
		(stroke
			(width 0)
			(type default)
		)
	)
	(wire
		(pts
			(xy 161.29 181.61) (xy 177.8 181.61)
		)
		(stroke
			(width 0)
			(type default)
		)
	)
	(wire
		(pts
			(xy 125.73 73.66) (xy 143.51 73.66)
		)
		(stroke
			(width 0)
			(type default)
		)
	)
	(bus
		(pts
			(xy 180.34 102.87) (xy 179.07 104.14)
		)
		(stroke
			(width 0)
			(type default)
		)
	)
	(wire
		(pts
			(xy 64.77 166.37) (xy 81.28 166.37)
		)
		(stroke
			(width 0)
			(type default)
		)
	)
	(bus
		(pts
			(xy 66.04 30.48) (xy 67.31 31.75)
		)
		(stroke
			(width 0)
			(type default)
		)
	)
	(bus
		(pts
			(xy 394.97 81.28) (xy 394.97 83.82)
		)
		(stroke
			(width 0)
			(type default)
		)
	)
	(bus
		(pts
			(xy 179.07 166.37) (xy 179.07 168.91)
		)
		(stroke
			(width 0)
			(type default)
		)
	)
	(wire
		(pts
			(xy 181.61 60.96) (xy 198.12 60.96)
		)
		(stroke
			(width 0)
			(type default)
		)
	)
	(bus
		(pts
			(xy 262.89 48.26) (xy 262.89 50.8)
		)
		(stroke
			(width 0)
			(type default)
		)
	)
	(bus
		(pts
			(xy 260.35 115.57) (xy 261.62 115.57)
		)
		(stroke
			(width 0)
			(type default)
		)
	)
	(bus
		(pts
			(xy 302.26 184.15) (xy 302.26 186.69)
		)
		(stroke
			(width 0)
			(type default)
		)
	)
	(wire
		(pts
			(xy 107.95 246.38) (xy 93.98 246.38)
		)
		(stroke
			(width 0)
			(type default)
		)
	)
	(wire
		(pts
			(xy 121.92 153.67) (xy 138.43 153.67)
		)
		(stroke
			(width 0)
			(type default)
		)
	)
	(wire
		(pts
			(xy 76.2 236.22) (xy 74.93 236.22)
		)
		(stroke
			(width 0)
			(type default)
		)
	)
	(wire
		(pts
			(xy 264.16 52.07) (xy 279.4 52.07)
		)
		(stroke
			(width 0)
			(type default)
		)
	)
	(wire
		(pts
			(xy 200.66 127) (xy 217.17 127)
		)
		(stroke
			(width 0)
			(type default)
		)
	)
	(wire
		(pts
			(xy 64.77 151.13) (xy 81.28 151.13)
		)
		(stroke
			(width 0)
			(type default)
		)
	)
	(wire
		(pts
			(xy 177.8 162.56) (xy 161.29 162.56)
		)
		(stroke
			(width 0)
			(type default)
		)
	)
	(wire
		(pts
			(xy 284.48 72.39) (xy 307.34 72.39)
		)
		(stroke
			(width 0)
			(type default)
		)
	)
	(wire
		(pts
			(xy 161.29 118.11) (xy 177.8 118.11)
		)
		(stroke
			(width 0)
			(type default)
		)
	)
	(wire
		(pts
			(xy 378.46 110.49) (xy 393.7 110.49)
		)
		(stroke
			(width 0)
			(type default)
		)
	)
	(bus
		(pts
			(xy 262.89 116.84) (xy 262.89 119.38)
		)
		(stroke
			(width 0)
			(type default)
		)
	)
	(wire
		(pts
			(xy 26.67 77.47) (xy 46.99 77.47)
		)
		(stroke
			(width 0)
			(type default)
		)
	)
	(bus
		(pts
			(xy 67.31 40.64) (xy 67.31 38.1)
		)
		(stroke
			(width 0)
			(type default)
		)
	)
	(bus
		(pts
			(xy 374.65 191.77) (xy 374.65 194.31)
		)
		(stroke
			(width 0)
			(type default)
		)
	)
	(wire
		(pts
			(xy 63.5 64.77) (xy 78.74 64.77)
		)
		(stroke
			(width 0)
			(type default)
		)
	)
	(wire
		(pts
			(xy 200.66 152.4) (xy 217.17 152.4)
		)
		(stroke
			(width 0)
			(type default)
		)
	)
	(wire
		(pts
			(xy 303.53 185.42) (xy 321.31 185.42)
		)
		(stroke
			(width 0)
			(type default)
		)
	)
	(wire
		(pts
			(xy 116.84 278.13) (xy 116.84 274.32)
		)
		(stroke
			(width 0)
			(type default)
		)
	)
	(wire
		(pts
			(xy 66.04 222.25) (xy 66.04 223.52)
		)
		(stroke
			(width 0)
			(type default)
		)
	)
	(bus
		(pts
			(xy 260.35 90.17) (xy 261.62 90.17)
		)
		(stroke
			(width 0)
			(type default)
		)
	)
	(wire
		(pts
			(xy 200.66 111.76) (xy 217.17 111.76)
		)
		(stroke
			(width 0)
			(type default)
		)
	)
	(wire
		(pts
			(xy 284.48 92.71) (xy 307.34 92.71)
		)
		(stroke
			(width 0)
			(type default)
		)
	)
	(bus
		(pts
			(xy 374.65 156.21) (xy 374.65 158.75)
		)
		(stroke
			(width 0)
			(type default)
		)
	)
	(bus
		(pts
			(xy 262.89 66.04) (xy 262.89 68.58)
		)
		(stroke
			(width 0)
			(type default)
		)
	)
	(bus
		(pts
			(xy 218.44 189.23) (xy 219.71 187.96)
		)
		(stroke
			(width 0)
			(type default)
		)
	)
	(wire
		(pts
			(xy 264.16 92.71) (xy 279.4 92.71)
		)
		(stroke
			(width 0)
			(type default)
		)
	)
	(wire
		(pts
			(xy 303.53 152.4) (xy 321.31 152.4)
		)
		(stroke
			(width 0)
			(type default)
		)
	)
	(wire
		(pts
			(xy 284.48 128.27) (xy 307.34 128.27)
		)
		(stroke
			(width 0)
			(type default)
		)
	)
	(wire
		(pts
			(xy 370.84 107.95) (xy 393.7 107.95)
		)
		(stroke
			(width 0)
			(type default)
		)
	)
	(bus
		(pts
			(xy 302.26 151.13) (xy 302.26 153.67)
		)
		(stroke
			(width 0)
			(type default)
		)
	)
	(wire
		(pts
			(xy 161.29 191.77) (xy 177.8 191.77)
		)
		(stroke
			(width 0)
			(type default)
		)
	)
	(wire
		(pts
			(xy 264.16 82.55) (xy 279.4 82.55)
		)
		(stroke
			(width 0)
			(type default)
		)
	)
	(wire
		(pts
			(xy 205.74 269.24) (xy 205.74 270.51)
		)
		(stroke
			(width 0)
			(type default)
		)
	)
	(wire
		(pts
			(xy 26.67 82.55) (xy 46.99 82.55)
		)
		(stroke
			(width 0)
			(type default)
		)
	)
	(bus
		(pts
			(xy 179.07 110.49) (xy 179.07 113.03)
		)
		(stroke
			(width 0)
			(type default)
		)
	)
	(bus
		(pts
			(xy 199.39 68.58) (xy 199.39 72.39)
		)
		(stroke
			(width 0)
			(type default)
		)
	)
	(wire
		(pts
			(xy 161.29 189.23) (xy 177.8 189.23)
		)
		(stroke
			(width 0)
			(type default)
		)
	)
	(bus
		(pts
			(xy 302.26 148.59) (xy 302.26 151.13)
		)
		(stroke
			(width 0)
			(type default)
		)
	)
	(wire
		(pts
			(xy 57.15 241.3) (xy 43.18 241.3)
		)
		(stroke
			(width 0)
			(type default)
		)
	)
	(wire
		(pts
			(xy 138.43 113.03) (xy 121.92 113.03)
		)
		(stroke
			(width 0)
			(type default)
		)
	)
	(wire
		(pts
			(xy 121.92 140.97) (xy 138.43 140.97)
		)
		(stroke
			(width 0)
			(type default)
		)
	)
	(wire
		(pts
			(xy 200.66 166.37) (xy 217.17 166.37)
		)
		(stroke
			(width 0)
			(type default)
		)
	)
	(wire
		(pts
			(xy 63.5 80.01) (xy 78.74 80.01)
		)
		(stroke
			(width 0)
			(type default)
		)
	)
	(wire
		(pts
			(xy 284.48 97.79) (xy 307.34 97.79)
		)
		(stroke
			(width 0)
			(type default)
		)
	)
	(wire
		(pts
			(xy 284.48 102.87) (xy 307.34 102.87)
		)
		(stroke
			(width 0)
			(type default)
		)
	)
	(wire
		(pts
			(xy 264.16 102.87) (xy 279.4 102.87)
		)
		(stroke
			(width 0)
			(type default)
		)
	)
	(wire
		(pts
			(xy 264.16 41.91) (xy 279.4 41.91)
		)
		(stroke
			(width 0)
			(type default)
		)
	)
	(wire
		(pts
			(xy 292.1 69.85) (xy 307.34 69.85)
		)
		(stroke
			(width 0)
			(type default)
		)
	)
	(wire
		(pts
			(xy 161.29 196.85) (xy 177.8 196.85)
		)
		(stroke
			(width 0)
			(type default)
		)
	)
	(polyline
		(pts
			(xy 245.11 207.01) (xy 245.11 11.43)
		)
		(stroke
			(width 0)
			(type default)
		)
	)
	(wire
		(pts
			(xy 274.32 262.89) (xy 290.83 262.89)
		)
		(stroke
			(width 0)
			(type default)
		)
	)
	(wire
		(pts
			(xy 123.19 236.22) (xy 137.16 236.22)
		)
		(stroke
			(width 0)
			(type default)
		)
	)
	(wire
		(pts
			(xy 135.89 238.76) (xy 137.16 238.76)
		)
		(stroke
			(width 0)
			(type default)
		)
	)
	(wire
		(pts
			(xy 121.92 161.29) (xy 138.43 161.29)
		)
		(stroke
			(width 0)
			(type default)
		)
	)
	(bus
		(pts
			(xy 201.93 49.53) (xy 200.66 49.53)
		)
		(stroke
			(width 0)
			(type default)
		)
	)
	(wire
		(pts
			(xy 177.8 167.64) (xy 161.29 167.64)
		)
		(stroke
			(width 0)
			(type default)
		)
	)
	(wire
		(pts
			(xy 292.1 120.65) (xy 307.34 120.65)
		)
		(stroke
			(width 0)
			(type default)
		)
	)
	(wire
		(pts
			(xy 57.15 252.73) (xy 43.18 252.73)
		)
		(stroke
			(width 0)
			(type default)
		)
	)
	(wire
		(pts
			(xy 101.6 232.41) (xy 101.6 233.68)
		)
		(stroke
			(width 0)
			(type default)
		)
	)
	(bus
		(pts
			(xy 218.44 195.58) (xy 218.44 198.12)
		)
		(stroke
			(width 0)
			(type default)
		)
	)
	(bus
		(pts
			(xy 302.26 181.61) (xy 302.26 184.15)
		)
		(stroke
			(width 0)
			(type default)
		)
	)
	(wire
		(pts
			(xy 121.92 173.99) (xy 132.08 173.99)
		)
		(stroke
			(width 0)
			(type default)
		)
	)
	(wire
		(pts
			(xy 200.66 175.26) (xy 217.17 175.26)
		)
		(stroke
			(width 0)
			(type default)
		)
	)
	(wire
		(pts
			(xy 373.38 162.56) (xy 355.6 162.56)
		)
		(stroke
			(width 0)
			(type default)
		)
	)
	(wire
		(pts
			(xy 68.58 35.56) (xy 78.74 35.56)
		)
		(stroke
			(width 0)
			(type default)
		)
	)
	(bus
		(pts
			(xy 262.89 101.6) (xy 262.89 104.14)
		)
		(stroke
			(width 0)
			(type default)
		)
	)
	(wire
		(pts
			(xy 222.25 267.97) (xy 223.52 267.97)
		)
		(stroke
			(width 0)
			(type default)
		)
	)
	(bus
		(pts
			(xy 200.66 49.53) (xy 199.39 50.8)
		)
		(stroke
			(width 0)
			(type default)
		)
	)
	(bus
		(pts
			(xy 374.65 170.18) (xy 374.65 172.72)
		)
		(stroke
			(width 0)
			(type default)
		)
	)
	(wire
		(pts
			(xy 125.73 41.91) (xy 137.16 41.91)
		)
		(stroke
			(width 0)
			(type default)
		)
	)
	(wire
		(pts
			(xy 303.53 195.58) (xy 321.31 195.58)
		)
		(stroke
			(width 0)
			(type default)
		)
	)
	(wire
		(pts
			(xy 200.66 107.95) (xy 217.17 107.95)
		)
		(stroke
			(width 0)
			(type default)
		)
	)
	(wire
		(pts
			(xy 76.2 238.76) (xy 62.23 238.76)
		)
		(stroke
			(width 0)
			(type default)
		)
	)
	(wire
		(pts
			(xy 209.55 237.49) (xy 209.55 234.95)
		)
		(stroke
			(width 0)
			(type default)
		)
	)
	(wire
		(pts
			(xy 200.66 148.59) (xy 217.17 148.59)
		)
		(stroke
			(width 0)
			(type default)
		)
	)
	(wire
		(pts
			(xy 350.52 92.71) (xy 393.7 92.71)
		)
		(stroke
			(width 0)
			(type default)
		)
	)
	(wire
		(pts
			(xy 350.52 85.09) (xy 373.38 85.09)
		)
		(stroke
			(width 0)
			(type default)
		)
	)
	(wire
		(pts
			(xy 52.07 77.47) (xy 60.96 77.47)
		)
		(stroke
			(width 0)
			(type default)
		)
	)
	(wire
		(pts
			(xy 181.61 73.66) (xy 198.12 73.66)
		)
		(stroke
			(width 0)
			(type default)
		)
	)
	(wire
		(pts
			(xy 64.77 115.57) (xy 81.28 115.57)
		)
		(stroke
			(width 0)
			(type default)
		)
	)
	(wire
		(pts
			(xy 74.93 236.22) (xy 74.93 233.68)
		)
		(stroke
			(width 0)
			(type default)
		)
	)
	(bus
		(pts
			(xy 218.44 110.49) (xy 218.44 113.03)
		)
		(stroke
			(width 0)
			(type default)
		)
	)
	(wire
		(pts
			(xy 181.61 54.61) (xy 198.12 54.61)
		)
		(stroke
			(width 0)
			(type default)
		)
	)
	(polyline
		(pts
			(xy 245.11 207.01) (xy 245.11 208.915)
		)
		(stroke
			(width 0)
			(type default)
		)
	)
	(wire
		(pts
			(xy 209.55 265.43) (xy 209.55 262.89)
		)
		(stroke
			(width 0)
			(type default)
		)
	)
	(wire
		(pts
			(xy 96.52 250.19) (xy 96.52 248.92)
		)
		(stroke
			(width 0)
			(type default)
		)
	)
	(wire
		(pts
			(xy 161.29 153.67) (xy 177.8 153.67)
		)
		(stroke
			(width 0)
			(type default)
		)
	)
	(bus
		(pts
			(xy 66.04 36.83) (xy 67.31 38.1)
		)
		(stroke
			(width 0)
			(type default)
		)
	)
	(bus
		(pts
			(xy 200.66 80.01) (xy 199.39 81.28)
		)
		(stroke
			(width 0)
			(type default)
		)
	)
	(wire
		(pts
			(xy 218.44 265.43) (xy 223.52 265.43)
		)
		(stroke
			(width 0)
			(type default)
		)
	)
	(wire
		(pts
			(xy 292.1 85.09) (xy 307.34 85.09)
		)
		(stroke
			(width 0)
			(type default)
		)
	)
	(wire
		(pts
			(xy 181.61 76.2) (xy 198.12 76.2)
		)
		(stroke
			(width 0)
			(type default)
		)
	)
	(bus
		(pts
			(xy 262.89 99.06) (xy 262.89 101.6)
		)
		(stroke
			(width 0)
			(type default)
		)
	)
	(wire
		(pts
			(xy 115.57 233.68) (xy 137.16 233.68)
		)
		(stroke
			(width 0)
			(type default)
		)
	)
	(wire
		(pts
			(xy 373.38 160.02) (xy 355.6 160.02)
		)
		(stroke
			(width 0)
			(type default)
		)
	)
	(wire
		(pts
			(xy 161.29 120.65) (xy 177.8 120.65)
		)
		(stroke
			(width 0)
			(type default)
		)
	)
	(bus
		(pts
			(xy 374.65 181.61) (xy 375.92 180.34)
		)
		(stroke
			(width 0)
			(type default)
		)
	)
	(wire
		(pts
			(xy 292.1 130.81) (xy 307.34 130.81)
		)
		(stroke
			(width 0)
			(type default)
		)
	)
	(bus
		(pts
			(xy 219.71 102.87) (xy 218.44 104.14)
		)
		(stroke
			(width 0)
			(type default)
		)
	)
	(bus
		(pts
			(xy 302.26 189.23) (xy 302.26 191.77)
		)
		(stroke
			(width 0)
			(type default)
		)
	)
	(wire
		(pts
			(xy 350.52 59.69) (xy 373.38 59.69)
		)
		(stroke
			(width 0)
			(type default)
		)
	)
	(wire
		(pts
			(xy 350.52 118.11) (xy 393.7 118.11)
		)
		(stroke
			(width 0)
			(type default)
		)
	)
	(bus
		(pts
			(xy 397.51 39.37) (xy 396.24 39.37)
		)
		(stroke
			(width 0)
			(type default)
		)
	)
	(wire
		(pts
			(xy 60.96 77.47) (xy 78.74 77.47)
		)
		(stroke
			(width 0)
			(type default)
		)
	)
	(wire
		(pts
			(xy 209.55 234.95) (xy 223.52 234.95)
		)
		(stroke
			(width 0)
			(type default)
		)
	)
	(wire
		(pts
			(xy 303.53 160.02) (xy 321.31 160.02)
		)
		(stroke
			(width 0)
			(type default)
		)
	)
	(bus
		(pts
			(xy 374.65 203.2) (xy 374.65 205.74)
		)
		(stroke
			(width 0)
			(type default)
		)
	)
	(wire
		(pts
			(xy 125.73 78.74) (xy 143.51 78.74)
		)
		(stroke
			(width 0)
			(type default)
		)
	)
	(wire
		(pts
			(xy 264.16 130.81) (xy 287.02 130.81)
		)
		(stroke
			(width 0)
			(type default)
		)
	)
	(wire
		(pts
			(xy 266.7 265.43) (xy 266.7 267.97)
		)
		(stroke
			(width 0)
			(type default)
		)
	)
	(wire
		(pts
			(xy 161.29 186.69) (xy 177.8 186.69)
		)
		(stroke
			(width 0)
			(type default)
		)
	)
	(bus
		(pts
			(xy 394.97 66.04) (xy 394.97 81.28)
		)
		(stroke
			(width 0)
			(type default)
		)
	)
	(wire
		(pts
			(xy 52.07 80.01) (xy 59.69 80.01)
		)
		(stroke
			(width 0)
			(type default)
		)
	)
	(wire
		(pts
			(xy 125.73 55.88) (xy 143.51 55.88)
		)
		(stroke
			(width 0)
			(type default)
		)
	)
	(wire
		(pts
			(xy 264.16 74.93) (xy 287.02 74.93)
		)
		(stroke
			(width 0)
			(type default)
		)
	)
	(wire
		(pts
			(xy 303.53 179.07) (xy 321.31 179.07)
		)
		(stroke
			(width 0)
			(type default)
		)
	)
	(bus
		(pts
			(xy 374.65 175.26) (xy 374.65 177.8)
		)
		(stroke
			(width 0)
			(type default)
		)
	)
	(wire
		(pts
			(xy 116.84 262.89) (xy 116.84 264.16)
		)
		(stroke
			(width 0)
			(type default)
		)
	)
	(wire
		(pts
			(xy 64.77 125.73) (xy 81.28 125.73)
		)
		(stroke
			(width 0)
			(type default)
		)
	)
	(wire
		(pts
			(xy 135.89 245.11) (xy 135.89 243.84)
		)
		(stroke
			(width 0)
			(type default)
		)
	)
	(bus
		(pts
			(xy 262.89 68.58) (xy 262.89 71.12)
		)
		(stroke
			(width 0)
			(type default)
		)
	)
	(wire
		(pts
			(xy 181.61 69.85) (xy 198.12 69.85)
		)
		(stroke
			(width 0)
			(type default)
		)
	)
	(bus
		(pts
			(xy 262.89 96.52) (xy 262.89 99.06)
		)
		(stroke
			(width 0)
			(type default)
		)
	)
	(wire
		(pts
			(xy 264.16 125.73) (xy 287.02 125.73)
		)
		(stroke
			(width 0)
			(type default)
		)
	)
	(bus
		(pts
			(xy 218.44 162.56) (xy 218.44 165.1)
		)
		(stroke
			(width 0)
			(type default)
		)
	)
	(bus
		(pts
			(xy 374.65 148.59) (xy 375.92 147.32)
		)
		(stroke
			(width 0)
			(type default)
		)
	)
	(wire
		(pts
			(xy 125.73 63.5) (xy 143.51 63.5)
		)
		(stroke
			(width 0)
			(type default)
		)
	)
	(wire
		(pts
			(xy 121.92 156.21) (xy 138.43 156.21)
		)
		(stroke
			(width 0)
			(type default)
		)
	)
	(wire
		(pts
			(xy 264.16 135.89) (xy 287.02 135.89)
		)
		(stroke
			(width 0)
			(type default)
		)
	)
	(bus
		(pts
			(xy 179.07 123.19) (xy 179.07 125.73)
		)
		(stroke
			(width 0)
			(type default)
		)
	)
	(bus
		(pts
			(xy 199.39 53.34) (xy 199.39 57.15)
		)
		(stroke
			(width 0)
			(type default)
		)
	)
	(bus
		(pts
			(xy 218.44 191.77) (xy 218.44 195.58)
		)
		(stroke
			(width 0)
			(type default)
		)
	)
	(bus
		(pts
			(xy 394.97 116.84) (xy 394.97 132.08)
		)
		(stroke
			(width 0)
			(type default)
		)
	)
	(wire
		(pts
			(xy 284.48 52.07) (xy 307.34 52.07)
		)
		(stroke
			(width 0)
			(type default)
		)
	)
	(wire
		(pts
			(xy 177.8 172.72) (xy 161.29 172.72)
		)
		(stroke
			(width 0)
			(type default)
		)
	)
	(bus
		(pts
			(xy 179.07 195.58) (xy 179.07 198.12)
		)
		(stroke
			(width 0)
			(type default)
		)
	)
	(wire
		(pts
			(xy 292.1 100.33) (xy 307.34 100.33)
		)
		(stroke
			(width 0)
			(type default)
		)
	)
	(wire
		(pts
			(xy 205.74 262.89) (xy 209.55 262.89)
		)
		(stroke
			(width 0)
			(type default)
		)
	)
	(bus
		(pts
			(xy 218.44 168.91) (xy 218.44 171.45)
		)
		(stroke
			(width 0)
			(type default)
		)
	)
	(bus
		(pts
			(xy 374.65 208.28) (xy 374.65 210.82)
		)
		(stroke
			(width 0)
			(type default)
		)
	)
	(wire
		(pts
			(xy 59.69 74.93) (xy 78.74 74.93)
		)
		(stroke
			(width 0)
			(type default)
		)
	)
	(wire
		(pts
			(xy 121.92 168.91) (xy 138.43 168.91)
		)
		(stroke
			(width 0)
			(type default)
		)
	)
	(bus
		(pts
			(xy 262.89 50.8) (xy 262.89 53.34)
		)
		(stroke
			(width 0)
			(type default)
		)
	)
	(wire
		(pts
			(xy 121.92 151.13) (xy 138.43 151.13)
		)
		(stroke
			(width 0)
			(type default)
		)
	)
	(bus
		(pts
			(xy 218.44 171.45) (xy 218.44 173.99)
		)
		(stroke
			(width 0)
			(type default)
		)
	)
	(wire
		(pts
			(xy 135.89 243.84) (xy 135.89 238.76)
		)
		(stroke
			(width 0)
			(type default)
		)
	)
	(wire
		(pts
			(xy 262.89 265.43) (xy 266.7 265.43)
		)
		(stroke
			(width 0)
			(type default)
		)
	)
	(bus
		(pts
			(xy 394.97 55.88) (xy 394.97 58.42)
		)
		(stroke
			(width 0)
			(type default)
		)
	)
	(bus
		(pts
			(xy 218.44 165.1) (xy 218.44 168.91)
		)
		(stroke
			(width 0)
			(type default)
		)
	)
	(wire
		(pts
			(xy 66.04 223.52) (xy 74.93 223.52)
		)
		(stroke
			(width 0)
			(type default)
		)
	)
	(wire
		(pts
			(xy 350.52 82.55) (xy 365.76 82.55)
		)
		(stroke
			(width 0)
			(type default)
		)
	)
	(wire
		(pts
			(xy 205.74 233.68) (xy 205.74 234.95)
		)
		(stroke
			(width 0)
			(type default)
		)
	)
	(wire
		(pts
			(xy 55.88 248.92) (xy 43.18 248.92)
		)
		(stroke
			(width 0)
			(type default)
		)
	)
	(bus
		(pts
			(xy 262.89 129.54) (xy 262.89 132.08)
		)
		(stroke
			(width 0)
			(type default)
		)
	)
	(wire
		(pts
			(xy 184.15 238.76) (xy 168.91 238.76)
		)
		(stroke
			(width 0)
			(type default)
		)
	)
	(wire
		(pts
			(xy 292.1 125.73) (xy 307.34 125.73)
		)
		(stroke
			(width 0)
			(type default)
		)
	)
	(bus
		(pts
			(xy 64.77 30.48) (xy 66.04 30.48)
		)
		(stroke
			(width 0)
			(type default)
		)
	)
	(wire
		(pts
			(xy 63.5 59.69) (xy 74.93 59.69)
		)
		(stroke
			(width 0)
			(type default)
		)
	)
	(wire
		(pts
			(xy 350.52 41.91) (xy 393.7 41.91)
		)
		(stroke
			(width 0)
			(type default)
		)
	)
	(wire
		(pts
			(xy 264.16 123.19) (xy 279.4 123.19)
		)
		(stroke
			(width 0)
			(type default)
		)
	)
	(bus
		(pts
			(xy 262.89 91.44) (xy 262.89 93.98)
		)
		(stroke
			(width 0)
			(type default)
		)
	)
	(wire
		(pts
			(xy 26.67 80.01) (xy 46.99 80.01)
		)
		(stroke
			(width 0)
			(type default)
		)
	)
	(wire
		(pts
			(xy 303.53 149.86) (xy 321.31 149.86)
		)
		(stroke
			(width 0)
			(type default)
		)
	)
	(wire
		(pts
			(xy 68.58 39.37) (xy 78.74 39.37)
		)
		(stroke
			(width 0)
			(type default)
		)
	)
	(bus
		(pts
			(xy 179.07 104.14) (xy 179.07 106.68)
		)
		(stroke
			(width 0)
			(type default)
		)
	)
	(bus
		(pts
			(xy 140.97 30.48) (xy 139.7 30.48)
		)
		(stroke
			(width 0)
			(type default)
		)
	)
	(bus
		(pts
			(xy 179.07 113.03) (xy 179.07 116.84)
		)
		(stroke
			(width 0)
			(type default)
		)
	)
	(wire
		(pts
			(xy 373.38 157.48) (xy 355.6 157.48)
		)
		(stroke
			(width 0)
			(type default)
		)
	)
	(wire
		(pts
			(xy 262.89 262.89) (xy 274.32 262.89)
		)
		(stroke
			(width 0)
			(type default)
		)
	)
	(bus
		(pts
			(xy 218.44 153.67) (xy 218.44 157.48)
		)
		(stroke
			(width 0)
			(type default)
		)
	)
	(wire
		(pts
			(xy 264.16 59.69) (xy 287.02 59.69)
		)
		(stroke
			(width 0)
			(type default)
		)
	)
	(wire
		(pts
			(xy 355.6 195.58) (xy 373.38 195.58)
		)
		(stroke
			(width 0)
			(type default)
		)
	)
	(wire
		(pts
			(xy 284.48 133.35) (xy 307.34 133.35)
		)
		(stroke
			(width 0)
			(type default)
		)
	)
	(wire
		(pts
			(xy 205.74 261.62) (xy 205.74 262.89)
		)
		(stroke
			(width 0)
			(type default)
		)
	)
	(wire
		(pts
			(xy 205.74 241.3) (xy 205.74 242.57)
		)
		(stroke
			(width 0)
			(type default)
		)
	)
	(wire
		(pts
			(xy 74.93 59.69) (xy 77.47 62.23)
		)
		(stroke
			(width 0)
			(type default)
		)
	)
	(wire
		(pts
			(xy 350.52 67.31) (xy 393.7 67.31)
		)
		(stroke
			(width 0)
			(type default)
		)
	)
	(bus
		(pts
			(xy 374.65 194.31) (xy 374.65 203.2)
		)
		(stroke
			(width 0)
			(type default)
		)
	)
	(bus
		(pts
			(xy 262.89 73.66) (xy 262.89 76.2)
		)
		(stroke
			(width 0)
			(type default)
		)
	)
	(wire
		(pts
			(xy 373.38 152.4) (xy 355.6 152.4)
		)
		(stroke
			(width 0)
			(type default)
		)
	)
	(wire
		(pts
			(xy 264.16 110.49) (xy 287.02 110.49)
		)
		(stroke
			(width 0)
			(type default)
		)
	)
	(wire
		(pts
			(xy 292.1 74.93) (xy 307.34 74.93)
		)
		(stroke
			(width 0)
			(type default)
		)
	)
	(wire
		(pts
			(xy 205.74 234.95) (xy 205.74 236.22)
		)
		(stroke
			(width 0)
			(type default)
		)
	)
	(wire
		(pts
			(xy 303.53 209.55) (xy 321.31 209.55)
		)
		(stroke
			(width 0)
			(type default)
		)
	)
	(wire
		(pts
			(xy 274.32 234.95) (xy 274.32 240.03)
		)
		(stroke
			(width 0)
			(type default)
		)
	)
	(bus
		(pts
			(xy 139.7 36.83) (xy 138.43 38.1)
		)
		(stroke
			(width 0)
			(type default)
		)
	)
	(wire
		(pts
			(xy 284.48 67.31) (xy 307.34 67.31)
		)
		(stroke
			(width 0)
			(type default)
		)
	)
	(wire
		(pts
			(xy 292.1 80.01) (xy 307.34 80.01)
		)
		(stroke
			(width 0)
			(type default)
		)
	)
	(wire
		(pts
			(xy 355.6 207.01) (xy 373.38 207.01)
		)
		(stroke
			(width 0)
			(type default)
		)
	)
	(wire
		(pts
			(xy 355.6 193.04) (xy 373.38 193.04)
		)
		(stroke
			(width 0)
			(type default)
		)
	)
	(wire
		(pts
			(xy 161.29 147.32) (xy 177.8 147.32)
		)
		(stroke
			(width 0)
			(type default)
		)
	)
	(wire
		(pts
			(xy 355.6 212.09) (xy 373.38 212.09)
		)
		(stroke
			(width 0)
			(type default)
		)
	)
	(wire
		(pts
			(xy 242.57 234.95) (xy 257.81 234.95)
		)
		(stroke
			(width 0)
			(type default)
		)
	)
	(bus
		(pts
			(xy 218.44 151.13) (xy 218.44 153.67)
		)
		(stroke
			(width 0)
			(type default)
		)
	)
	(bus
		(pts
			(xy 218.44 173.99) (xy 218.44 176.53)
		)
		(stroke
			(width 0)
			(type default)
		)
	)
	(wire
		(pts
			(xy 130.81 264.16) (xy 130.81 265.43)
		)
		(stroke
			(width 0)
			(type default)
		)
	)
	(wire
		(pts
			(xy 64.77 158.75) (xy 81.28 158.75)
		)
		(stroke
			(width 0)
			(type default)
		)
	)
	(wire
		(pts
			(xy 303.53 204.47) (xy 321.31 204.47)
		)
		(stroke
			(width 0)
			(type default)
		)
	)
	(bus
		(pts
			(xy 302.26 208.28) (xy 302.26 210.82)
		)
		(stroke
			(width 0)
			(type default)
		)
	)
	(bus
		(pts
			(xy 64.77 36.83) (xy 66.04 36.83)
		)
		(stroke
			(width 0)
			(type default)
		)
	)
	(wire
		(pts
			(xy 161.29 184.15) (xy 177.8 184.15)
		)
		(stroke
			(width 0)
			(type default)
		)
	)
	(bus
		(pts
			(xy 302.26 172.72) (xy 302.26 175.26)
		)
		(stroke
			(width 0)
			(type default)
		)
	)
	(wire
		(pts
			(xy 284.48 41.91) (xy 307.34 41.91)
		)
		(stroke
			(width 0)
			(type default)
		)
	)
	(wire
		(pts
			(xy 378.46 85.09) (xy 393.7 85.09)
		)
		(stroke
			(width 0)
			(type default)
		)
	)
	(bus
		(pts
			(xy 374.65 161.29) (xy 374.65 170.18)
		)
		(stroke
			(width 0)
			(type default)
		)
	)
	(wire
		(pts
			(xy 262.89 234.95) (xy 274.32 234.95)
		)
		(stroke
			(width 0)
			(type default)
		)
	)
	(wire
		(pts
			(xy 71.12 171.45) (xy 81.28 171.45)
		)
		(stroke
			(width 0)
			(type default)
		)
	)
	(wire
		(pts
			(xy 69.85 252.73) (xy 69.85 255.27)
		)
		(stroke
			(width 0)
			(type default)
		)
	)
	(bus
		(pts
			(xy 218.44 106.68) (xy 218.44 110.49)
		)
		(stroke
			(width 0)
			(type default)
		)
	)
	(bus
		(pts
			(xy 179.07 171.45) (xy 179.07 173.99)
		)
		(stroke
			(width 0)
			(type default)
		)
	)
	(wire
		(pts
			(xy 123.19 241.3) (xy 137.16 241.3)
		)
		(stroke
			(width 0)
			(type default)
		)
	)
	(bus
		(pts
			(xy 218.44 157.48) (xy 218.44 160.02)
		)
		(stroke
			(width 0)
			(type default)
		)
	)
	(bus
		(pts
			(xy 262.89 81.28) (xy 262.89 83.82)
		)
		(stroke
			(width 0)
			(type default)
		)
	)
	(wire
		(pts
			(xy 264.16 85.09) (xy 287.02 85.09)
		)
		(stroke
			(width 0)
			(type default)
		)
	)
	(wire
		(pts
			(xy 200.66 196.85) (xy 217.17 196.85)
		)
		(stroke
			(width 0)
			(type default)
		)
	)
	(bus
		(pts
			(xy 262.89 45.72) (xy 262.89 48.26)
		)
		(stroke
			(width 0)
			(type default)
		)
	)
	(wire
		(pts
			(xy 121.92 158.75) (xy 138.43 158.75)
		)
		(stroke
			(width 0)
			(type default)
		)
	)
	(bus
		(pts
			(xy 374.65 184.15) (xy 374.65 186.69)
		)
		(stroke
			(width 0)
			(type default)
		)
	)
	(bus
		(pts
			(xy 218.44 116.84) (xy 218.44 119.38)
		)
		(stroke
			(width 0)
			(type default)
		)
	)
	(wire
		(pts
			(xy 121.92 163.83) (xy 138.43 163.83)
		)
		(stroke
			(width 0)
			(type default)
		)
	)
	(wire
		(pts
			(xy 242.57 262.89) (xy 257.81 262.89)
		)
		(stroke
			(width 0)
			(type default)
		)
	)
	(bus
		(pts
			(xy 302.26 191.77) (xy 302.26 194.31)
		)
		(stroke
			(width 0)
			(type default)
		)
	)
	(wire
		(pts
			(xy 200.66 190.5) (xy 217.17 190.5)
		)
		(stroke
			(width 0)
			(type default)
		)
	)
	(wire
		(pts
			(xy 205.74 262.89) (xy 205.74 264.16)
		)
		(stroke
			(width 0)
			(type default)
		)
	)
	(wire
		(pts
			(xy 373.38 154.94) (xy 355.6 154.94)
		)
		(stroke
			(width 0)
			(type default)
		)
	)
	(bus
		(pts
			(xy 374.65 158.75) (xy 374.65 161.29)
		)
		(stroke
			(width 0)
			(type default)
		)
	)
	(wire
		(pts
			(xy 350.52 135.89) (xy 373.38 135.89)
		)
		(stroke
			(width 0)
			(type default)
		)
	)
	(wire
		(pts
			(xy 57.15 246.38) (xy 43.18 246.38)
		)
		(stroke
			(width 0)
			(type default)
		)
	)
	(wire
		(pts
			(xy 303.53 193.04) (xy 321.31 193.04)
		)
		(stroke
			(width 0)
			(type default)
		)
	)
	(wire
		(pts
			(xy 121.92 143.51) (xy 138.43 143.51)
		)
		(stroke
			(width 0)
			(type default)
		)
	)
	(bus
		(pts
			(xy 375.92 147.32) (xy 381 147.32)
		)
		(stroke
			(width 0)
			(type default)
		)
	)
	(wire
		(pts
			(xy 107.95 243.84) (xy 93.98 243.84)
		)
		(stroke
			(width 0)
			(type default)
		)
	)
	(wire
		(pts
			(xy 161.29 107.95) (xy 177.8 107.95)
		)
		(stroke
			(width 0)
			(type default)
		)
	)
	(wire
		(pts
			(xy 292.1 54.61) (xy 307.34 54.61)
		)
		(stroke
			(width 0)
			(type default)
		)
	)
	(wire
		(pts
			(xy 264.16 46.99) (xy 279.4 46.99)
		)
		(stroke
			(width 0)
			(type default)
		)
	)
	(bus
		(pts
			(xy 262.89 104.14) (xy 262.89 106.68)
		)
		(stroke
			(width 0)
			(type default)
		)
	)
	(wire
		(pts
			(xy 161.29 124.46) (xy 177.8 124.46)
		)
		(stroke
			(width 0)
			(type default)
		)
	)
	(bus
		(pts
			(xy 302.26 181.61) (xy 300.99 180.34)
		)
		(stroke
			(width 0)
			(type default)
		)
	)
	(bus
		(pts
			(xy 179.07 152.4) (xy 179.07 154.94)
		)
		(stroke
			(width 0)
			(type default)
		)
	)
	(wire
		(pts
			(xy 373.38 173.99) (xy 355.6 173.99)
		)
		(stroke
			(width 0)
			(type default)
		)
	)
	(bus
		(pts
			(xy 179.07 193.04) (xy 179.07 195.58)
		)
		(stroke
			(width 0)
			(type default)
		)
	)
	(wire
		(pts
			(xy 121.92 125.73) (xy 138.43 125.73)
		)
		(stroke
			(width 0)
			(type default)
		)
	)
	(bus
		(pts
			(xy 262.89 78.74) (xy 262.89 81.28)
		)
		(stroke
			(width 0)
			(type default)
		)
	)
	(wire
		(pts
			(xy 107.95 238.76) (xy 93.98 238.76)
		)
		(stroke
			(width 0)
			(type default)
		)
	)
	(bus
		(pts
			(xy 179.07 161.29) (xy 179.07 163.83)
		)
		(stroke
			(width 0)
			(type default)
		)
	)
	(wire
		(pts
			(xy 177.8 177.8) (xy 161.29 177.8)
		)
		(stroke
			(width 0)
			(type default)
		)
	)
	(bus
		(pts
			(xy 179.07 148.59) (xy 179.07 152.4)
		)
		(stroke
			(width 0)
			(type default)
		)
	)
	(bus
		(pts
			(xy 179.07 119.38) (xy 179.07 123.19)
		)
		(stroke
			(width 0)
			(type default)
		)
	)
	(wire
		(pts
			(xy 59.69 80.01) (xy 59.69 74.93)
		)
		(stroke
			(width 0)
			(type default)
		)
	)
	(bus
		(pts
			(xy 397.51 64.77) (xy 396.24 64.77)
		)
		(stroke
			(width 0)
			(type default)
		)
	)
	(wire
		(pts
			(xy 284.48 77.47) (xy 307.34 77.47)
		)
		(stroke
			(width 0)
			(type default)
		)
	)
	(wire
		(pts
			(xy 64.77 118.11) (xy 81.28 118.11)
		)
		(stroke
			(width 0)
			(type default)
		)
	)
	(bus
		(pts
			(xy 260.35 39.37) (xy 261.62 39.37)
		)
		(stroke
			(width 0)
			(type default)
		)
	)
	(wire
		(pts
			(xy 93.98 233.68) (xy 101.6 233.68)
		)
		(stroke
			(width 0)
			(type default)
		)
	)
	(bus
		(pts
			(xy 179.07 154.94) (xy 179.07 158.75)
		)
		(stroke
			(width 0)
			(type default)
		)
	)
	(bus
		(pts
			(xy 262.89 40.64) (xy 262.89 43.18)
		)
		(stroke
			(width 0)
			(type default)
		)
	)
	(wire
		(pts
			(xy 142.24 255.27) (xy 142.24 262.89)
		)
		(stroke
			(width 0)
			(type default)
		)
	)
	(wire
		(pts
			(xy 64.77 135.89) (xy 81.28 135.89)
		)
		(stroke
			(width 0)
			(type default)
		)
	)
	(wire
		(pts
			(xy 292.1 110.49) (xy 307.34 110.49)
		)
		(stroke
			(width 0)
			(type default)
		)
	)
	(wire
		(pts
			(xy 200.66 161.29) (xy 217.17 161.29)
		)
		(stroke
			(width 0)
			(type default)
		)
	)
	(wire
		(pts
			(xy 370.84 82.55) (xy 393.7 82.55)
		)
		(stroke
			(width 0)
			(type default)
		)
	)
	(wire
		(pts
			(xy 121.92 120.65) (xy 138.43 120.65)
		)
		(stroke
			(width 0)
			(type default)
		)
	)
	(wire
		(pts
			(xy 200.66 124.46) (xy 217.17 124.46)
		)
		(stroke
			(width 0)
			(type default)
		)
	)
	(bus
		(pts
			(xy 140.97 36.83) (xy 139.7 36.83)
		)
		(stroke
			(width 0)
			(type default)
		)
	)
	(wire
		(pts
			(xy 373.38 149.86) (xy 355.6 149.86)
		)
		(stroke
			(width 0)
			(type default)
		)
	)
	(wire
		(pts
			(xy 74.93 62.23) (xy 77.47 59.69)
		)
		(stroke
			(width 0)
			(type default)
		)
	)
	(wire
		(pts
			(xy 64.77 156.21) (xy 81.28 156.21)
		)
		(stroke
			(width 0)
			(type default)
		)
	)
	(wire
		(pts
			(xy 137.16 243.84) (xy 135.89 243.84)
		)
		(stroke
			(width 0)
			(type default)
		)
	)
	(wire
		(pts
			(xy 181.61 52.07) (xy 198.12 52.07)
		)
		(stroke
			(width 0)
			(type default)
		)
	)
	(wire
		(pts
			(xy 373.38 179.07) (xy 355.6 179.07)
		)
		(stroke
			(width 0)
			(type default)
		)
	)
	(wire
		(pts
			(xy 76.2 246.38) (xy 62.23 246.38)
		)
		(stroke
			(width 0)
			(type default)
		)
	)
	(wire
		(pts
			(xy 274.32 262.89) (xy 274.32 267.97)
		)
		(stroke
			(width 0)
			(type default)
		)
	)
	(wire
		(pts
			(xy 121.92 123.19) (xy 138.43 123.19)
		)
		(stroke
			(width 0)
			(type default)
		)
	)
	(wire
		(pts
			(xy 200.66 118.11) (xy 217.17 118.11)
		)
		(stroke
			(width 0)
			(type default)
		)
	)
	(bus
		(pts
			(xy 199.39 81.28) (xy 199.39 83.82)
		)
		(stroke
			(width 0)
			(type default)
		)
	)
	(bus
		(pts
			(xy 374.65 153.67) (xy 374.65 156.21)
		)
		(stroke
			(width 0)
			(type default)
		)
	)
	(wire
		(pts
			(xy 170.18 236.22) (xy 170.18 245.11)
		)
		(stroke
			(width 0)
			(type default)
		)
	)
	(wire
		(pts
			(xy 355.6 185.42) (xy 373.38 185.42)
		)
		(stroke
			(width 0)
			(type default)
		)
	)
	(wire
		(pts
			(xy 76.2 243.84) (xy 62.23 243.84)
		)
		(stroke
			(width 0)
			(type default)
		)
	)
	(wire
		(pts
			(xy 64.77 120.65) (xy 81.28 120.65)
		)
		(stroke
			(width 0)
			(type default)
		)
	)
	(bus
		(pts
			(xy 262.89 121.92) (xy 262.89 124.46)
		)
		(stroke
			(width 0)
			(type default)
		)
	)
	(wire
		(pts
			(xy 303.53 190.5) (xy 321.31 190.5)
		)
		(stroke
			(width 0)
			(type default)
		)
	)
	(wire
		(pts
			(xy 266.7 265.43) (xy 290.83 265.43)
		)
		(stroke
			(width 0)
			(type default)
		)
	)
	(wire
		(pts
			(xy 68.58 41.91) (xy 78.74 41.91)
		)
		(stroke
			(width 0)
			(type default)
		)
	)
	(bus
		(pts
			(xy 179.07 185.42) (xy 179.07 187.96)
		)
		(stroke
			(width 0)
			(type default)
		)
	)
	(wire
		(pts
			(xy 292.1 105.41) (xy 307.34 105.41)
		)
		(stroke
			(width 0)
			(type default)
		)
	)
	(wire
		(pts
			(xy 184.15 233.68) (xy 168.91 233.68)
		)
		(stroke
			(width 0)
			(type default)
		)
	)
	(bus
		(pts
			(xy 199.39 57.15) (xy 199.39 59.69)
		)
		(stroke
			(width 0)
			(type default)
		)
	)
	(bus
		(pts
			(xy 179.07 182.88) (xy 179.07 185.42)
		)
		(stroke
			(width 0)
			(type default)
		)
	)
	(wire
		(pts
			(xy 138.43 107.95) (xy 121.92 107.95)
		)
		(stroke
			(width 0)
			(type default)
		)
	)
	(wire
		(pts
			(xy 125.73 71.12) (xy 143.51 71.12)
		)
		(stroke
			(width 0)
			(type default)
		)
	)
	(bus
		(pts
			(xy 179.07 176.53) (xy 179.07 180.34)
		)
		(stroke
			(width 0)
			(type default)
		)
	)
	(wire
		(pts
			(xy 77.47 59.69) (xy 78.74 59.69)
		)
		(stroke
			(width 0)
			(type default)
		)
	)
	(wire
		(pts
			(xy 161.29 111.76) (xy 177.8 111.76)
		)
		(stroke
			(width 0)
			(type default)
		)
	)
	(bus
		(pts
			(xy 179.07 116.84) (xy 179.07 119.38)
		)
		(stroke
			(width 0)
			(type default)
		)
	)
	(wire
		(pts
			(xy 264.16 120.65) (xy 287.02 120.65)
		)
		(stroke
			(width 0)
			(type default)
		)
	)
	(wire
		(pts
			(xy 71.12 173.99) (xy 81.28 173.99)
		)
		(stroke
			(width 0)
			(type default)
		)
	)
	(wire
		(pts
			(xy 264.16 128.27) (xy 279.4 128.27)
		)
		(stroke
			(width 0)
			(type default)
		)
	)
	(wire
		(pts
			(xy 355.6 187.96) (xy 373.38 187.96)
		)
		(stroke
			(width 0)
			(type default)
		)
	)
	(bus
		(pts
			(xy 262.89 53.34) (xy 262.89 55.88)
		)
		(stroke
			(width 0)
			(type default)
		)
	)
	(bus
		(pts
			(xy 394.97 91.44) (xy 396.24 90.17)
		)
		(stroke
			(width 0)
			(type default)
		)
	)
	(wire
		(pts
			(xy 76.2 233.68) (xy 74.93 233.68)
		)
		(stroke
			(width 0)
			(type default)
		)
	)
	(wire
		(pts
			(xy 125.73 53.34) (xy 143.51 53.34)
		)
		(stroke
			(width 0)
			(type default)
		)
	)
	(wire
		(pts
			(xy 264.16 44.45) (xy 287.02 44.45)
		)
		(stroke
			(width 0)
			(type default)
		)
	)
	(bus
		(pts
			(xy 262.89 71.12) (xy 262.89 73.66)
		)
		(stroke
			(width 0)
			(type default)
		)
	)
	(wire
		(pts
			(xy 121.92 171.45) (xy 132.08 171.45)
		)
		(stroke
			(width 0)
			(type default)
		)
	)
	(polyline
		(pts
			(xy 11.43 208.915) (xy 299.72 208.915)
		)
		(stroke
			(width 0)
			(type default)
		)
	)
	(wire
		(pts
			(xy 200.66 163.83) (xy 217.17 163.83)
		)
		(stroke
			(width 0)
			(type default)
		)
	)
	(wire
		(pts
			(xy 130.81 261.62) (xy 130.81 264.16)
		)
		(stroke
			(width 0)
			(type default)
		)
	)
	(wire
		(pts
			(xy 161.29 199.39) (xy 177.8 199.39)
		)
		(stroke
			(width 0)
			(type default)
		)
	)
	(wire
		(pts
			(xy 121.92 166.37) (xy 138.43 166.37)
		)
		(stroke
			(width 0)
			(type default)
		)
	)
	(wire
		(pts
			(xy 64.77 153.67) (xy 81.28 153.67)
		)
		(stroke
			(width 0)
			(type default)
		)
	)
	(wire
		(pts
			(xy 121.92 135.89) (xy 138.43 135.89)
		)
		(stroke
			(width 0)
			(type default)
		)
	)
	(wire
		(pts
			(xy 264.16 80.01) (xy 287.02 80.01)
		)
		(stroke
			(width 0)
			(type default)
		)
	)
	(wire
		(pts
			(xy 63.5 72.39) (xy 78.74 72.39)
		)
		(stroke
			(width 0)
			(type default)
		)
	)
	(wire
		(pts
			(xy 303.53 157.48) (xy 321.31 157.48)
		)
		(stroke
			(width 0)
			(type default)
		)
	)
	(wire
		(pts
			(xy 264.16 133.35) (xy 279.4 133.35)
		)
		(stroke
			(width 0)
			(type default)
		)
	)
	(bus
		(pts
			(xy 300.99 180.34) (xy 295.91 180.34)
		)
		(stroke
			(width 0)
			(type default)
		)
	)
	(wire
		(pts
			(xy 350.52 107.95) (xy 365.76 107.95)
		)
		(stroke
			(width 0)
			(type default)
		)
	)
	(wire
		(pts
			(xy 200.66 154.94) (xy 217.17 154.94)
		)
		(stroke
			(width 0)
			(type default)
		)
	)
	(bus
		(pts
			(xy 302.26 170.18) (xy 302.26 172.72)
		)
		(stroke
			(width 0)
			(type default)
		)
	)
	(wire
		(pts
			(xy 355.6 209.55) (xy 373.38 209.55)
		)
		(stroke
			(width 0)
			(type default)
		)
	)
	(bus
		(pts
			(xy 138.43 34.29) (xy 138.43 31.75)
		)
		(stroke
			(width 0)
			(type default)
		)
	)
	(wire
		(pts
			(xy 303.53 173.99) (xy 321.31 173.99)
		)
		(stroke
			(width 0)
			(type default)
		)
	)
	(wire
		(pts
			(xy 64.77 161.29) (xy 81.28 161.29)
		)
		(stroke
			(width 0)
			(type default)
		)
	)
	(bus
		(pts
			(xy 302.26 186.69) (xy 302.26 189.23)
		)
		(stroke
			(width 0)
			(type default)
		)
	)
	(wire
		(pts
			(xy 200.66 193.04) (xy 217.17 193.04)
		)
		(stroke
			(width 0)
			(type default)
		)
	)
	(wire
		(pts
			(xy 200.66 146.05) (xy 217.17 146.05)
		)
		(stroke
			(width 0)
			(type default)
		)
	)
	(wire
		(pts
			(xy 142.24 273.05) (xy 142.24 267.97)
		)
		(stroke
			(width 0)
			(type default)
		)
	)
	(wire
		(pts
			(xy 373.38 176.53) (xy 355.6 176.53)
		)
		(stroke
			(width 0)
			(type default)
		)
	)
	(bus
		(pts
			(xy 218.44 144.78) (xy 218.44 147.32)
		)
		(stroke
			(width 0)
			(type default)
		)
	)
	(bus
		(pts
			(xy 180.34 144.78) (xy 179.07 146.05)
		)
		(stroke
			(width 0)
			(type default)
		)
	)
	(bus
		(pts
			(xy 201.93 64.77) (xy 200.66 64.77)
		)
		(stroke
			(width 0)
			(type default)
		)
	)
	(bus
		(pts
			(xy 300.99 147.32) (xy 295.91 147.32)
		)
		(stroke
			(width 0)
			(type default)
		)
	)
	(wire
		(pts
			(xy 64.77 113.03) (xy 81.28 113.03)
		)
		(stroke
			(width 0)
			(type default)
		)
	)
	(wire
		(pts
			(xy 264.16 72.39) (xy 279.4 72.39)
		)
		(stroke
			(width 0)
			(type default)
		)
	)
	(wire
		(pts
			(xy 124.46 271.78) (xy 124.46 264.16)
		)
		(stroke
			(width 0)
			(type default)
		)
	)
	(wire
		(pts
			(xy 43.18 255.27) (xy 57.15 255.27)
		)
		(stroke
			(width 0)
			(type default)
		)
	)
	(bus
		(pts
			(xy 374.65 189.23) (xy 374.65 191.77)
		)
		(stroke
			(width 0)
			(type default)
		)
	)
	(wire
		(pts
			(xy 242.57 265.43) (xy 257.81 265.43)
		)
		(stroke
			(width 0)
			(type default)
		)
	)
	(wire
		(pts
			(xy 181.61 91.44) (xy 198.12 91.44)
		)
		(stroke
			(width 0)
			(type default)
		)
	)
	(wire
		(pts
			(xy 57.15 238.76) (xy 43.18 238.76)
		)
		(stroke
			(width 0)
			(type default)
		)
	)
	(wire
		(pts
			(xy 121.92 128.27) (xy 138.43 128.27)
		)
		(stroke
			(width 0)
			(type default)
		)
	)
	(wire
		(pts
			(xy 123.19 271.78) (xy 124.46 271.78)
		)
		(stroke
			(width 0)
			(type default)
		)
	)
	(bus
		(pts
			(xy 262.89 124.46) (xy 262.89 127)
		)
		(stroke
			(width 0)
			(type default)
		)
	)
	(wire
		(pts
			(xy 62.23 252.73) (xy 69.85 252.73)
		)
		(stroke
			(width 0)
			(type default)
		)
	)
	(wire
		(pts
			(xy 125.73 35.56) (xy 137.16 35.56)
		)
		(stroke
			(width 0)
			(type default)
		)
	)
	(wire
		(pts
			(xy 264.16 95.25) (xy 287.02 95.25)
		)
		(stroke
			(width 0)
			(type default)
		)
	)
	(wire
		(pts
			(xy 161.29 114.3) (xy 177.8 114.3)
		)
		(stroke
			(width 0)
			(type default)
		)
	)
	(bus
		(pts
			(xy 179.07 187.96) (xy 179.07 190.5)
		)
		(stroke
			(width 0)
			(type default)
		)
	)
	(wire
		(pts
			(xy 115.57 233.68) (xy 115.57 234.95)
		)
		(stroke
			(width 0)
			(type default)
		)
	)
	(bus
		(pts
			(xy 179.07 190.5) (xy 179.07 193.04)
		)
		(stroke
			(width 0)
			(type default)
		)
	)
	(bus
		(pts
			(xy 394.97 106.68) (xy 394.97 109.22)
		)
		(stroke
			(width 0)
			(type default)
		)
	)
	(wire
		(pts
			(xy 209.55 262.89) (xy 223.52 262.89)
		)
		(stroke
			(width 0)
			(type default)
		)
	)
	(wire
		(pts
			(xy 161.29 127) (xy 177.8 127)
		)
		(stroke
			(width 0)
			(type default)
		)
	)
	(wire
		(pts
			(xy 303.53 154.94) (xy 321.31 154.94)
		)
		(stroke
			(width 0)
			(type default)
		)
	)
	(bus
		(pts
			(xy 199.39 72.39) (xy 199.39 74.93)
		)
		(stroke
			(width 0)
			(type default)
		)
	)
	(wire
		(pts
			(xy 138.43 105.41) (xy 121.92 105.41)
		)
		(stroke
			(width 0)
			(type default)
		)
	)
	(wire
		(pts
			(xy 264.16 105.41) (xy 287.02 105.41)
		)
		(stroke
			(width 0)
			(type default)
		)
	)
	(wire
		(pts
			(xy 64.77 138.43) (xy 81.28 138.43)
		)
		(stroke
			(width 0)
			(type default)
		)
	)
	(bus
		(pts
			(xy 218.44 104.14) (xy 218.44 106.68)
		)
		(stroke
			(width 0)
			(type default)
		)
	)
	(label "USB2.D-"
		(at 128.27 35.56 0)
		(effects
			(font
				(size 1.27 1.27)
			)
			(justify left bottom)
		)
	)
	(label "PCIe_{C5x4}.RX1+"
		(at 64.77 156.21 0)
		(effects
			(font
				(size 1.27 1.27)
			)
			(justify left bottom)
		)
	)
	(label "DP2.TX1_C+"
		(at 295.91 97.79 0)
		(effects
			(font
				(size 1.27 1.27)
			)
			(justify left bottom)
		)
	)
	(label "DP3.AUX+"
		(at 392.43 133.35 180)
		(effects
			(font
				(size 1.27 1.27)
			)
			(justify right bottom)
		)
	)
	(label "DP2.TX1_C-"
		(at 295.91 100.33 0)
		(effects
			(font
				(size 1.27 1.27)
			)
			(justify left bottom)
		)
	)
	(label "PCIe_{C3x2}.RX0+"
		(at 200.66 170.18 0)
		(effects
			(font
				(size 1.27 1.27)
			)
			(justify left bottom)
		)
	)
	(label "DP0.AUX+"
		(at 392.43 57.15 180)
		(effects
			(font
				(size 1.27 1.27)
			)
			(justify right bottom)
		)
	)
	(label "SFI_CLK+"
		(at 252.73 234.95 180)
		(effects
			(font
				(size 1.27 1.27)
			)
			(justify right bottom)
		)
	)
	(label "DP0.AUX_C-"
		(at 350.52 59.69 0)
		(effects
			(font
				(size 1.27 1.27)
			)
			(justify left bottom)
		)
	)
	(label "PCIe_{C2x1}.RX0-"
		(at 161.29 127 0)
		(effects
			(font
				(size 1.27 1.27)
			)
			(justify left bottom)
		)
	)
	(label "DP3.AUX_C+"
		(at 350.52 133.35 0)
		(effects
			(font
				(size 1.27 1.27)
			)
			(justify left bottom)
		)
	)
	(label "CAM0.CSI2_D1+"
		(at 303.53 193.04 0)
		(effects
			(font
				(size 1.27 1.27)
			)
			(justify left bottom)
		)
	)
	(label "PCIe_{C5x4}.TX2+"
		(at 138.43 161.29 180)
		(effects
			(font
				(size 1.27 1.27)
			)
			(justify right bottom)
		)
	)
	(label "CAM2.CSI4_CLK+"
		(at 373.38 149.86 180)
		(effects
			(font
				(size 1.27 1.27)
			)
			(justify right bottom)
		)
	)
	(label "PCIe_{C5x4}.CLK-"
		(at 161.29 156.21 0)
		(effects
			(font
				(size 1.27 1.27)
			)
			(justify left bottom)
		)
	)
	(label "CAM1.CSI1_D1-"
		(at 303.53 179.07 0)
		(effects
			(font
				(size 1.27 1.27)
			)
			(justify left bottom)
		)
	)
	(label "DP1.AUX_C+"
		(at 350.52 82.55 0)
		(effects
			(font
				(size 1.27 1.27)
			)
			(justify left bottom)
		)
	)
	(label "CAM3.CSI7_D0-"
		(at 373.38 207.01 180)
		(effects
			(font
				(size 1.27 1.27)
			)
			(justify right bottom)
		)
	)
	(label "PCIe_{C5x4}.RX3+"
		(at 161.29 196.85 0)
		(effects
			(font
				(size 1.27 1.27)
			)
			(justify left bottom)
		)
	)
	(label "DP3.AUX-"
		(at 392.43 135.89 180)
		(effects
			(font
				(size 1.27 1.27)
			)
			(justify right bottom)
		)
	)
	(label "PCIe_{C1x1}.~{CLKREQ}"
		(at 143.51 53.34 180)
		(effects
			(font
				(size 1.27 1.27)
			)
			(justify right bottom)
		)
	)
	(label "C2_CLK+"
		(at 252.73 262.89 180)
		(effects
			(font
				(size 1.27 1.27)
			)
			(justify right bottom)
		)
	)
	(label "CAM1.CSI0_CLK-"
		(at 303.53 152.4 0)
		(effects
			(font
				(size 1.27 1.27)
			)
			(justify left bottom)
		)
	)
	(label "DP2.TX2-"
		(at 265.43 105.41 0)
		(effects
			(font
				(size 1.27 1.27)
			)
			(justify left bottom)
		)
	)
	(label "PCIe_{C5x4}.RX0+"
		(at 161.29 181.61 0)
		(effects
			(font
				(size 1.27 1.27)
			)
			(justify left bottom)
		)
	)
	(label "DP2.TX3_C+"
		(at 295.91 107.95 0)
		(effects
			(font
				(size 1.27 1.27)
			)
			(justify left bottom)
		)
	)
	(label "PCIe_{C1x1}.CLK+"
		(at 63.5 80.01 0)
		(effects
			(font
				(size 1.27 1.27)
			)
			(justify left bottom)
		)
	)
	(label "PCIe_{C5x4}.RX3+"
		(at 64.77 166.37 0)
		(effects
			(font
				(size 1.27 1.27)
			)
			(justify left bottom)
		)
	)
	(label "USBSS2.TX+"
		(at 138.43 115.57 180)
		(effects
			(font
				(size 1.27 1.27)
			)
			(justify right bottom)
		)
	)
	(label "USBSS1.RX-"
		(at 181.61 76.2 0)
		(effects
			(font
				(size 1.27 1.27)
			)
			(justify left bottom)
		)
	)
	(label "USBSS2.TX+"
		(at 181.61 82.55 0)
		(effects
			(font
				(size 1.27 1.27)
			)
			(justify left bottom)
		)
	)
	(label "PCIe_{C2x1}.~{CLKREQ}"
		(at 161.29 107.95 0)
		(effects
			(font
				(size 1.27 1.27)
			)
			(justify left bottom)
		)
	)
	(label "CAM0.CSI2_CLK+"
		(at 303.53 182.88 0)
		(effects
			(font
				(size 1.27 1.27)
			)
			(justify left bottom)
		)
	)
	(label "SFI.TX+"
		(at 132.08 171.45 180)
		(effects
			(font
				(size 1.27 1.27)
			)
			(justify right bottom)
		)
	)
	(label "DP1.TX1_C+"
		(at 295.91 72.39 0)
		(effects
			(font
				(size 1.27 1.27)
			)
			(justify left bottom)
		)
	)
	(label "NVJTAG_SEL"
		(at 43.18 252.73 0)
		(effects
			(font
				(size 1.27 1.27)
			)
			(justify left bottom)
		)
	)
	(label "CAM1.CSI1_D0+"
		(at 303.53 171.45 0)
		(effects
			(font
				(size 1.27 1.27)
			)
			(justify left bottom)
		)
	)
	(label "DP3.TX1_C+"
		(at 295.91 123.19 0)
		(effects
			(font
				(size 1.27 1.27)
			)
			(justify left bottom)
		)
	)
	(label "JTAG_TMS"
		(at 43.18 238.76 0)
		(effects
			(font
				(size 1.27 1.27)
			)
			(justify left bottom)
		)
	)
	(label "PCIe_{C5x4}.TX0-"
		(at 138.43 153.67 180)
		(effects
			(font
				(size 1.27 1.27)
			)
			(justify right bottom)
		)
	)
	(label "SFI.RX+"
		(at 200.66 196.85 0)
		(effects
			(font
				(size 1.27 1.27)
			)
			(justify left bottom)
		)
	)
	(label "PCIe_{C3x2}.CLK+"
		(at 200.66 152.4 0)
		(effects
			(font
				(size 1.27 1.27)
			)
			(justify left bottom)
		)
	)
	(label "CAM0.CSI3_D1-"
		(at 303.53 212.09 0)
		(effects
			(font
				(size 1.27 1.27)
			)
			(justify left bottom)
		)
	)
	(label "DP1.AUX+"
		(at 392.43 82.55 180)
		(effects
			(font
				(size 1.27 1.27)
			)
			(justify right bottom)
		)
	)
	(label "CAM3.CSI6_D1-"
		(at 373.38 195.58 180)
		(effects
			(font
				(size 1.27 1.27)
			)
			(justify right bottom)
		)
	)
	(label "DP1.TX0+"
		(at 265.43 67.31 0)
		(effects
			(font
				(size 1.27 1.27)
			)
			(justify left bottom)
		)
	)
	(label "PCIe_{C1x1}.RX0-"
		(at 64.77 123.19 0)
		(effects
			(font
				(size 1.27 1.27)
			)
			(justify left bottom)
		)
	)
	(label "DP0.TX0+"
		(at 265.43 41.91 0)
		(effects
			(font
				(size 1.27 1.27)
			)
			(justify left bottom)
		)
	)
	(label "PCIe_{C3x2}.~{CLKREQ}"
		(at 143.51 58.42 180)
		(effects
			(font
				(size 1.27 1.27)
			)
			(justify right bottom)
		)
	)
	(label "DP3.TX3_C+"
		(at 295.91 133.35 0)
		(effects
			(font
				(size 1.27 1.27)
			)
			(justify left bottom)
		)
	)
	(label "DP1.TX2_C+"
		(at 295.91 77.47 0)
		(effects
			(font
				(size 1.27 1.27)
			)
			(justify left bottom)
		)
	)
	(label "DP0.TX3_C+"
		(at 295.91 57.15 0)
		(effects
			(font
				(size 1.27 1.27)
			)
			(justify left bottom)
		)
	)
	(label "PCIe_{C2x1}.~{RST}"
		(at 161.29 105.41 0)
		(effects
			(font
				(size 1.27 1.27)
			)
			(justify left bottom)
		)
	)
	(label "TC_JTAG_TMS"
		(at 107.95 238.76 180)
		(effects
			(font
				(size 1.27 1.27)
			)
			(justify right bottom)
		)
	)
	(label "USBSS1.RX+"
		(at 181.61 73.66 0)
		(effects
			(font
				(size 1.27 1.27)
			)
			(justify left bottom)
		)
	)
	(label "PCIe_{C3x2}.RX1+"
		(at 200.66 175.26 0)
		(effects
			(font
				(size 1.27 1.27)
			)
			(justify left bottom)
		)
	)
	(label "PCIe_{C3x2}.TX1+"
		(at 138.43 140.97 180)
		(effects
			(font
				(size 1.27 1.27)
			)
			(justify right bottom)
		)
	)
	(label "DP0.AUX-"
		(at 392.43 59.69 180)
		(effects
			(font
				(size 1.27 1.27)
			)
			(justify right bottom)
		)
	)
	(label "PCIe_{C1x1}.RX0+"
		(at 200.66 124.46 0)
		(effects
			(font
				(size 1.27 1.27)
			)
			(justify left bottom)
		)
	)
	(label "TC_JTAG_TDO"
		(at 184.15 243.84 180)
		(effects
			(font
				(size 1.27 1.27)
			)
			(justify right bottom)
		)
	)
	(label "USBSS1.TX+"
		(at 138.43 110.49 180)
		(effects
			(font
				(size 1.27 1.27)
			)
			(justify right bottom)
		)
	)
	(label "PCIe_{C2x1}R_CLK+"
		(at 63.5 74.93 0)
		(effects
			(font
				(size 1.27 1.27)
			)
			(justify left bottom)
		)
	)
	(label "C2_REFCLK-"
		(at 26.67 77.47 0)
		(effects
			(font
				(size 1.27 1.27)
			)
			(justify left bottom)
		)
	)
	(label "C2_CLK-"
		(at 252.73 265.43 180)
		(effects
			(font
				(size 1.27 1.27)
			)
			(justify right bottom)
		)
	)
	(label "TC_JTAG_TDI"
		(at 184.15 238.76 180)
		(effects
			(font
				(size 1.27 1.27)
			)
			(justify right bottom)
		)
	)
	(label "PCIe_{C2x1}.CLK-"
		(at 26.67 82.55 0)
		(effects
			(font
				(size 1.27 1.27)
			)
			(justify left bottom)
		)
	)
	(label "PCIe_{C3x2}.RX1-"
		(at 64.77 143.51 0)
		(effects
			(font
				(size 1.27 1.27)
			)
			(justify left bottom)
		)
	)
	(label "C2_REFCLK-"
		(at 290.83 265.43 180)
		(effects
			(font
				(size 1.27 1.27)
			)
			(justify right bottom)
		)
	)
	(label "USBSS2.RX+"
		(at 64.77 115.57 0)
		(effects
			(font
				(size 1.27 1.27)
			)
			(justify left bottom)
		)
	)
	(label "CAM2.CSI4_CLK-"
		(at 373.38 152.4 180)
		(effects
			(font
				(size 1.27 1.27)
			)
			(justify right bottom)
		)
	)
	(label "PCIe_{C5x4}.RX3-"
		(at 64.77 168.91 0)
		(effects
			(font
				(size 1.27 1.27)
			)
			(justify left bottom)
		)
	)
	(label "PCIe_{C3x2}.TX1-"
		(at 138.43 143.51 180)
		(effects
			(font
				(size 1.27 1.27)
			)
			(justify right bottom)
		)
	)
	(label "USBSS2.RX-"
		(at 181.61 91.44 0)
		(effects
			(font
				(size 1.27 1.27)
			)
			(justify left bottom)
		)
	)
	(label "USBSS0.RX+"
		(at 181.61 58.42 0)
		(effects
			(font
				(size 1.27 1.27)
			)
			(justify left bottom)
		)
	)
	(label "PCIe_{C2x1}.TX0-"
		(at 161.29 120.65 0)
		(effects
			(font
				(size 1.27 1.27)
			)
			(justify left bottom)
		)
	)
	(label "USB3.D+"
		(at 128.27 39.37 0)
		(effects
			(font
				(size 1.27 1.27)
			)
			(justify left bottom)
		)
	)
	(label "CAM1.CSI0_CLK+"
		(at 303.53 149.86 0)
		(effects
			(font
				(size 1.27 1.27)
			)
			(justify left bottom)
		)
	)
	(label "PCIe_{C1x1}.~{RST}"
		(at 200.66 105.41 0)
		(effects
			(font
				(size 1.27 1.27)
			)
			(justify left bottom)
		)
	)
	(label "DP2.TX0-"
		(at 265.43 95.25 0)
		(effects
			(font
				(size 1.27 1.27)
			)
			(justify left bottom)
		)
	)
	(label "USBSS2.RX-"
		(at 64.77 118.11 0)
		(effects
			(font
				(size 1.27 1.27)
			)
			(justify left bottom)
		)
	)
	(label "CAM2.CSI5_D1-"
		(at 373.38 179.07 180)
		(effects
			(font
				(size 1.27 1.27)
			)
			(justify right bottom)
		)
	)
	(label "DP1.TX2-"
		(at 265.43 80.01 0)
		(effects
			(font
				(size 1.27 1.27)
			)
			(justify left bottom)
		)
	)
	(label "DP3.AUX_C-"
		(at 350.52 135.89 0)
		(effects
			(font
				(size 1.27 1.27)
			)
			(justify left bottom)
		)
	)
	(label "DP1.TX0-"
		(at 265.43 69.85 0)
		(effects
			(font
				(size 1.27 1.27)
			)
			(justify left bottom)
		)
	)
	(label "PCIe_{C3x2}.TX1+"
		(at 200.66 163.83 0)
		(effects
			(font
				(size 1.27 1.27)
			)
			(justify left bottom)
		)
	)
	(label "USBSS0.RX-"
		(at 181.61 60.96 0)
		(effects
			(font
				(size 1.27 1.27)
			)
			(justify left bottom)
		)
	)
	(label "USB2.D+"
		(at 128.27 33.02 0)
		(effects
			(font
				(size 1.27 1.27)
			)
			(justify left bottom)
		)
	)
	(label "DP3.TX3+"
		(at 265.43 133.35 0)
		(effects
			(font
				(size 1.27 1.27)
			)
			(justify left bottom)
		)
	)
	(label "USBSS0.TX-"
		(at 138.43 107.95 180)
		(effects
			(font
				(size 1.27 1.27)
			)
			(justify right bottom)
		)
	)
	(label "USB1.D+"
		(at 77.47 39.37 180)
		(effects
			(font
				(size 1.27 1.27)
			)
			(justify right bottom)
		)
	)
	(label "CAM3.CSI6_D0+"
		(at 373.38 187.96 180)
		(effects
			(font
				(size 1.27 1.27)
			)
			(justify right bottom)
		)
	)
	(label "PCIe_{C3x2}.~{RST}"
		(at 200.66 146.05 0)
		(effects
			(font
				(size 1.27 1.27)
			)
			(justify left bottom)
		)
	)
	(label "SFI.TX-"
		(at 132.08 173.99 180)
		(effects
			(font
				(size 1.27 1.27)
			)
			(justify right bottom)
		)
	)
	(label "PCIe_{C3x2}.~{CLKREQ}"
		(at 200.66 148.59 0)
		(effects
			(font
				(size 1.27 1.27)
			)
			(justify left bottom)
		)
	)
	(label "TC_VCC"
		(at 123.19 233.68 0)
		(effects
			(font
				(size 1.27 1.27)
			)
			(justify left bottom)
		)
	)
	(label "DP2.TX3+"
		(at 265.43 107.95 0)
		(effects
			(font
				(size 1.27 1.27)
			)
			(justify left bottom)
		)
	)
	(label "PCIe_{C3x2}.RX1+"
		(at 64.77 140.97 0)
		(effects
			(font
				(size 1.27 1.27)
			)
			(justify left bottom)
		)
	)
	(label "DP1.TX3+"
		(at 265.43 82.55 0)
		(effects
			(font
				(size 1.27 1.27)
			)
			(justify left bottom)
		)
	)
	(label "USBSS0.TX-"
		(at 181.61 54.61 0)
		(effects
			(font
				(size 1.27 1.27)
			)
			(justify left bottom)
		)
	)
	(label "SFI.RX+"
		(at 71.12 171.45 0)
		(effects
			(font
				(size 1.27 1.27)
			)
			(justify left bottom)
		)
	)
	(label "PCIe_{C2x1}.RX0+"
		(at 161.29 124.46 0)
		(effects
			(font
				(size 1.27 1.27)
			)
			(justify left bottom)
		)
	)
	(label "CAM0.CSI3_D0-"
		(at 303.53 207.01 0)
		(effects
			(font
				(size 1.27 1.27)
			)
			(justify left bottom)
		)
	)
	(label "SFI_REFCLK+"
		(at 63.5 59.69 0)
		(effects
			(font
				(size 1.27 1.27)
			)
			(justify left bottom)
		)
	)
	(label "DP2.TX0_C+"
		(at 295.91 92.71 0)
		(effects
			(font
				(size 1.27 1.27)
			)
			(justify left bottom)
		)
	)
	(label "PCIe_{C3x2}.TX0+"
		(at 138.43 135.89 180)
		(effects
			(font
				(size 1.27 1.27)
			)
			(justify right bottom)
		)
	)
	(label "PCIe_{C5x4}.TX3-"
		(at 138.43 168.91 180)
		(effects
			(font
				(size 1.27 1.27)
			)
			(justify right bottom)
		)
	)
	(label "DP0.TX2+"
		(at 265.43 52.07 0)
		(effects
			(font
				(size 1.27 1.27)
			)
			(justify left bottom)
		)
	)
	(label "CAM0.CSI2_D0-"
		(at 303.53 190.5 0)
		(effects
			(font
				(size 1.27 1.27)
			)
			(justify left bottom)
		)
	)
	(label "DP2.AUX_C+"
		(at 350.52 107.95 0)
		(effects
			(font
				(size 1.27 1.27)
			)
			(justify left bottom)
		)
	)
	(label "PCIe_{C5x4}.TX1-"
		(at 138.43 158.75 180)
		(effects
			(font
				(size 1.27 1.27)
			)
			(justify right bottom)
		)
	)
	(label "PCIe_{C5x4}.~{CLKREQ}"
		(at 143.51 63.5 180)
		(effects
			(font
				(size 1.27 1.27)
			)
			(justify right bottom)
		)
	)
	(label "DP0.TX1_C-"
		(at 295.91 49.53 0)
		(effects
			(font
				(size 1.27 1.27)
			)
			(justify left bottom)
		)
	)
	(label "PCIe_{C5x4}.RX2-"
		(at 64.77 163.83 0)
		(effects
			(font
				(size 1.27 1.27)
			)
			(justify left bottom)
		)
	)
	(label "PCIe_{C3x2}.~{RST}"
		(at 143.51 73.66 180)
		(effects
			(font
				(size 1.27 1.27)
			)
			(justify right bottom)
		)
	)
	(label "PCIe_{C5x4}.RX0+"
		(at 64.77 151.13 0)
		(effects
			(font
				(size 1.27 1.27)
			)
			(justify left bottom)
		)
	)
	(label "PCIe_{C5x4}.TX2-"
		(at 161.29 172.72 0)
		(effects
			(font
				(size 1.27 1.27)
			)
			(justify left bottom)
		)
	)
	(label "CAM3.CSI7_D1+"
		(at 373.38 209.55 180)
		(effects
			(font
				(size 1.27 1.27)
			)
			(justify right bottom)
		)
	)
	(label "DP0.TX1_C+"
		(at 295.91 46.99 0)
		(effects
			(font
				(size 1.27 1.27)
			)
			(justify left bottom)
		)
	)
	(label "PCIe_{C5x4}.RX2+"
		(at 161.29 191.77 0)
		(effects
			(font
				(size 1.27 1.27)
			)
			(justify left bottom)
		)
	)
	(label "PCIe_{C1x1}.~{RST}"
		(at 143.51 68.58 180)
		(effects
			(font
				(size 1.27 1.27)
			)
			(justify right bottom)
		)
	)
	(label "DP0.TX2_C+"
		(at 295.91 52.07 0)
		(effects
			(font
				(size 1.27 1.27)
			)
			(justify left bottom)
		)
	)
	(label "DP0.TX1+"
		(at 265.43 46.99 0)
		(effects
			(font
				(size 1.27 1.27)
			)
			(justify left bottom)
		)
	)
	(label "DP2.TX2_C+"
		(at 295.91 102.87 0)
		(effects
			(font
				(size 1.27 1.27)
			)
			(justify left bottom)
		)
	)
	(label "CAM2.CSI4_D0+"
		(at 373.38 154.94 180)
		(effects
			(font
				(size 1.27 1.27)
			)
			(justify right bottom)
		)
	)
	(label "PCIe_{C1x1}.CLK-"
		(at 200.66 114.3 0)
		(effects
			(font
				(size 1.27 1.27)
			)
			(justify left bottom)
		)
	)
	(label "USBSS2.TX-"
		(at 181.61 85.09 0)
		(effects
			(font
				(size 1.27 1.27)
			)
			(justify left bottom)
		)
	)
	(label "DP0.TX3-"
		(at 265.43 59.69 0)
		(effects
			(font
				(size 1.27 1.27)
			)
			(justify left bottom)
		)
	)
	(label "TC_JTAG_TCK"
		(at 107.95 243.84 180)
		(effects
			(font
				(size 1.27 1.27)
			)
			(justify right bottom)
		)
	)
	(label "SFI.TX-"
		(at 200.66 193.04 0)
		(effects
			(font
				(size 1.27 1.27)
			)
			(justify left bottom)
		)
	)
	(label "DP0.TX1-"
		(at 265.43 49.53 0)
		(effects
			(font
				(size 1.27 1.27)
			)
			(justify left bottom)
		)
	)
	(label "DP3.TX1+"
		(at 265.43 123.19 0)
		(effects
			(font
				(size 1.27 1.27)
			)
			(justify left bottom)
		)
	)
	(label "DP3.TX3_C-"
		(at 295.91 135.89 0)
		(effects
			(font
				(size 1.27 1.27)
			)
			(justify left bottom)
		)
	)
	(label "PCIe_{C1x1}.CLK+"
		(at 200.66 111.76 0)
		(effects
			(font
				(size 1.27 1.27)
			)
			(justify left bottom)
		)
	)
	(label "DP2.TX3-"
		(at 265.43 110.49 0)
		(effects
			(font
				(size 1.27 1.27)
			)
			(justify left bottom)
		)
	)
	(label "JTAG_TDI"
		(at 43.18 241.3 0)
		(effects
			(font
				(size 1.27 1.27)
			)
			(justify left bottom)
		)
	)
	(label "USB3.D-"
		(at 128.27 41.91 0)
		(effects
			(font
				(size 1.27 1.27)
			)
			(justify left bottom)
		)
	)
	(label "DP3.TX0-"
		(at 265.43 120.65 0)
		(effects
			(font
				(size 1.27 1.27)
			)
			(justify left bottom)
		)
	)
	(label "USB0.D+"
		(at 77.47 33.02 180)
		(effects
			(font
				(size 1.27 1.27)
			)
			(justify right bottom)
		)
	)
	(label "CAM2.CSI5_D0+"
		(at 373.38 171.45 180)
		(effects
			(font
				(size 1.27 1.27)
			)
			(justify right bottom)
		)
	)
	(label "DP3.TX1_C-"
		(at 295.91 125.73 0)
		(effects
			(font
				(size 1.27 1.27)
			)
			(justify left bottom)
		)
	)
	(label "DP0.TX0-"
		(at 265.43 44.45 0)
		(effects
			(font
				(size 1.27 1.27)
			)
			(justify left bottom)
		)
	)
	(label "PCIe_{C1x1}.TX0+"
		(at 200.66 118.11 0)
		(effects
			(font
				(size 1.27 1.27)
			)
			(justify left bottom)
		)
	)
	(label "DP3.TX0+"
		(at 265.43 118.11 0)
		(effects
			(font
				(size 1.27 1.27)
			)
			(justify left bottom)
		)
	)
	(label "DP1.TX3_C-"
		(at 295.91 85.09 0)
		(effects
			(font
				(size 1.27 1.27)
			)
			(justify left bottom)
		)
	)
	(label "C2_REFCLK+"
		(at 290.83 262.89 180)
		(effects
			(font
				(size 1.27 1.27)
			)
			(justify right bottom)
		)
	)
	(label "PCIe_{C5x4}.TX1+"
		(at 161.29 165.1 0)
		(effects
			(font
				(size 1.27 1.27)
			)
			(justify left bottom)
		)
	)
	(label "DP3.TX0_C-"
		(at 295.91 120.65 0)
		(effects
			(font
				(size 1.27 1.27)
			)
			(justify left bottom)
		)
	)
	(label "JTAG_TDO"
		(at 43.18 246.38 0)
		(effects
			(font
				(size 1.27 1.27)
			)
			(justify left bottom)
		)
	)
	(label "PCIe_{C2x1}.CLK+"
		(at 26.67 80.01 0)
		(effects
			(font
				(size 1.27 1.27)
			)
			(justify left bottom)
		)
	)
	(label "CAM0.CSI2_CLK-"
		(at 303.53 185.42 0)
		(effects
			(font
				(size 1.27 1.27)
			)
			(justify left bottom)
		)
	)
	(label "PCIe_{C1x1}.TX0-"
		(at 138.43 123.19 180)
		(effects
			(font
				(size 1.27 1.27)
			)
			(justify right bottom)
		)
	)
	(label "TC_JTAG_TDI"
		(at 107.95 241.3 180)
		(effects
			(font
				(size 1.27 1.27)
			)
			(justify right bottom)
		)
	)
	(label "DP0.TX2-"
		(at 265.43 54.61 0)
		(effects
			(font
				(size 1.27 1.27)
			)
			(justify left bottom)
		)
	)
	(label "PCIe_{C5x4}.RX2-"
		(at 161.29 194.31 0)
		(effects
			(font
				(size 1.27 1.27)
			)
			(justify left bottom)
		)
	)
	(label "DP2.HPD"
		(at 392.43 92.71 180)
		(effects
			(font
				(size 1.27 1.27)
			)
			(justify right bottom)
		)
	)
	(label "CAM1.CSI0_D1+"
		(at 303.53 160.02 0)
		(effects
			(font
				(size 1.27 1.27)
			)
			(justify left bottom)
		)
	)
	(label "SFI_REFCLK-"
		(at 63.5 62.23 0)
		(effects
			(font
				(size 1.27 1.27)
			)
			(justify left bottom)
		)
	)
	(label "PCIe_{C3x2}.RX0-"
		(at 200.66 172.72 0)
		(effects
			(font
				(size 1.27 1.27)
			)
			(justify left bottom)
		)
	)
	(label "DP3.HPD"
		(at 392.43 118.11 180)
		(effects
			(font
				(size 1.27 1.27)
			)
			(justify right bottom)
		)
	)
	(label "PCIe_{C3x2}.CLK-"
		(at 63.5 72.39 0)
		(effects
			(font
				(size 1.27 1.27)
			)
			(justify left bottom)
		)
	)
	(label "PCIe_{C5x4}.TX1+"
		(at 138.43 156.21 180)
		(effects
			(font
				(size 1.27 1.27)
			)
			(justify right bottom)
		)
	)
	(label "PCIe_{C5x4}.RX0-"
		(at 64.77 153.67 0)
		(effects
			(font
				(size 1.27 1.27)
			)
			(justify left bottom)
		)
	)
	(label "PCIe_{C5x4}.~{RST}"
		(at 161.29 147.32 0)
		(effects
			(font
				(size 1.27 1.27)
			)
			(justify left bottom)
		)
	)
	(label "PCIe_{C3x2}.CLK+"
		(at 63.5 69.85 0)
		(effects
			(font
				(size 1.27 1.27)
			)
			(justify left bottom)
		)
	)
	(label "TC_JTAG_TDO"
		(at 107.95 246.38 180)
		(effects
			(font
				(size 1.27 1.27)
			)
			(justify right bottom)
		)
	)
	(label "CAM3.CSI7_D0+"
		(at 373.38 204.47 180)
		(effects
			(font
				(size 1.27 1.27)
			)
			(justify right bottom)
		)
	)
	(label "DP1.HPD"
		(at 392.43 67.31 180)
		(effects
			(font
				(size 1.27 1.27)
			)
			(justify right bottom)
		)
	)
	(label "PCIe_{C2x1}.TX0+"
		(at 138.43 125.73 180)
		(effects
			(font
				(size 1.27 1.27)
			)
			(justify right bottom)
		)
	)
	(label "PCIe_{C5x4}.TX3-"
		(at 161.29 177.8 0)
		(effects
			(font
				(size 1.27 1.27)
			)
			(justify left bottom)
		)
	)
	(label "SFI.RX-"
		(at 71.12 173.99 0)
		(effects
			(font
				(size 1.27 1.27)
			)
			(justify left bottom)
		)
	)
	(label "JTAG_TRST_N"
		(at 55.88 248.92 180)
		(effects
			(font
				(size 1.27 1.27)
			)
			(justify right bottom)
		)
	)
	(label "TC_JTAG_TMS"
		(at 123.19 236.22 0)
		(effects
			(font
				(size 1.27 1.27)
			)
			(justify left bottom)
		)
	)
	(label "DP1.AUX-"
		(at 392.43 85.09 180)
		(effects
			(font
				(size 1.27 1.27)
			)
			(justify right bottom)
		)
	)
	(label "SFI_REFCLK-"
		(at 290.83 237.49 180)
		(effects
			(font
				(size 1.27 1.27)
			)
			(justify right bottom)
		)
	)
	(label "PCIe_{C5x4}.TX3+"
		(at 161.29 175.26 0)
		(effects
			(font
				(size 1.27 1.27)
			)
			(justify left bottom)
		)
	)
	(label "SFI.RX-"
		(at 200.66 199.39 0)
		(effects
			(font
				(size 1.27 1.27)
			)
			(justify left bottom)
		)
	)
	(label "PCIe_{C3x2}.TX1-"
		(at 200.66 166.37 0)
		(effects
			(font
				(size 1.27 1.27)
			)
			(justify left bottom)
		)
	)
	(label "PCIe_{C5x4}.TX0+"
		(at 161.29 160.02 0)
		(effects
			(font
				(size 1.27 1.27)
			)
			(justify left bottom)
		)
	)
	(label "DP0.TX3+"
		(at 265.43 57.15 0)
		(effects
			(font
				(size 1.27 1.27)
			)
			(justify left bottom)
		)
	)
	(label "CAM3.CSI6_D0-"
		(at 373.38 190.5 180)
		(effects
			(font
				(size 1.27 1.27)
			)
			(justify right bottom)
		)
	)
	(label "CAM2.CSI5_D1+"
		(at 373.38 176.53 180)
		(effects
			(font
				(size 1.27 1.27)
			)
			(justify right bottom)
		)
	)
	(label "DP1.TX3-"
		(at 265.43 85.09 0)
		(effects
			(font
				(size 1.27 1.27)
			)
			(justify left bottom)
		)
	)
	(label "DP0.TX0_C-"
		(at 295.91 44.45 0)
		(effects
			(font
				(size 1.27 1.27)
			)
			(justify left bottom)
		)
	)
	(label "CAM3.CSI6_CLK-"
		(at 373.38 185.42 180)
		(effects
			(font
				(size 1.27 1.27)
			)
			(justify right bottom)
		)
	)
	(label "PCIe_{C5x4}.TX1-"
		(at 161.29 167.64 0)
		(effects
			(font
				(size 1.27 1.27)
			)
			(justify left bottom)
		)
	)
	(label "CAM1.CSI0_D0-"
		(at 303.53 157.48 0)
		(effects
			(font
				(size 1.27 1.27)
			)
			(justify left bottom)
		)
	)
	(label "PCIe_{C2x1}R_CLK-"
		(at 63.5 77.47 0)
		(effects
			(font
				(size 1.27 1.27)
			)
			(justify left bottom)
		)
	)
	(label "USBSS1.TX-"
		(at 138.43 113.03 180)
		(effects
			(font
				(size 1.27 1.27)
			)
			(justify right bottom)
		)
	)
	(label "PCIe_{C5x4}.TX0+"
		(at 138.43 151.13 180)
		(effects
			(font
				(size 1.27 1.27)
			)
			(justify right bottom)
		)
	)
	(label "PCIe_{C2x1}.TX0+"
		(at 161.29 118.11 0)
		(effects
			(font
				(size 1.27 1.27)
			)
			(justify left bottom)
		)
	)
	(label "JTAG_TCK"
		(at 43.18 243.84 0)
		(effects
			(font
				(size 1.27 1.27)
			)
			(justify left bottom)
		)
	)
	(label "PCIe_{C3x2}.RX1-"
		(at 200.66 177.8 0)
		(effects
			(font
				(size 1.27 1.27)
			)
			(justify left bottom)
		)
	)
	(label "DP3.TX2-"
		(at 265.43 130.81 0)
		(effects
			(font
				(size 1.27 1.27)
			)
			(justify left bottom)
		)
	)
	(label "CAM1.CSI0_D1-"
		(at 303.53 162.56 0)
		(effects
			(font
				(size 1.27 1.27)
			)
			(justify left bottom)
		)
	)
	(label "CAM0.CSI2_D0+"
		(at 303.53 187.96 0)
		(effects
			(font
				(size 1.27 1.27)
			)
			(justify left bottom)
		)
	)
	(label "C2_REFCLK+"
		(at 26.67 74.93 0)
		(effects
			(font
				(size 1.27 1.27)
			)
			(justify left bottom)
		)
	)
	(label "DP1.TX2_C-"
		(at 295.91 80.01 0)
		(effects
			(font
				(size 1.27 1.27)
			)
			(justify left bottom)
		)
	)
	(label "PCIe_{C3x2}.TX0-"
		(at 200.66 161.29 0)
		(effects
			(font
				(size 1.27 1.27)
			)
			(justify left bottom)
		)
	)
	(label "DP0.AUX_C+"
		(at 350.52 57.15 0)
		(effects
			(font
				(size 1.27 1.27)
			)
			(justify left bottom)
		)
	)
	(label "PCIe_{C1x1}.RX0-"
		(at 200.66 127 0)
		(effects
			(font
				(size 1.27 1.27)
			)
			(justify left bottom)
		)
	)
	(label "USBSS2.RX+"
		(at 181.61 88.9 0)
		(effects
			(font
				(size 1.27 1.27)
			)
			(justify left bottom)
		)
	)
	(label "PCIe_{C2x1}.RX0-"
		(at 64.77 128.27 0)
		(effects
			(font
				(size 1.27 1.27)
			)
			(justify left bottom)
		)
	)
	(label "USBSS1.RX+"
		(at 64.77 110.49 0)
		(effects
			(font
				(size 1.27 1.27)
			)
			(justify left bottom)
		)
	)
	(label "PCIe_{C5x4}.RX1-"
		(at 64.77 158.75 0)
		(effects
			(font
				(size 1.27 1.27)
			)
			(justify left bottom)
		)
	)
	(label "DP2.TX1+"
		(at 265.43 97.79 0)
		(effects
			(font
				(size 1.27 1.27)
			)
			(justify left bottom)
		)
	)
	(label "PCIe_{C1x1}.RX0+"
		(at 64.77 120.65 0)
		(effects
			(font
				(size 1.27 1.27)
			)
			(justify left bottom)
		)
	)
	(label "DP3.TX2+"
		(at 265.43 128.27 0)
		(effects
			(font
				(size 1.27 1.27)
			)
			(justify left bottom)
		)
	)
	(label "DP3.TX1-"
		(at 265.43 125.73 0)
		(effects
			(font
				(size 1.27 1.27)
			)
			(justify left bottom)
		)
	)
	(label "USBSS0.TX+"
		(at 138.43 105.41 180)
		(effects
			(font
				(size 1.27 1.27)
			)
			(justify right bottom)
		)
	)
	(label "CAM1.CSI1_D1+"
		(at 303.53 176.53 0)
		(effects
			(font
				(size 1.27 1.27)
			)
			(justify left bottom)
		)
	)
	(label "USBSS0.RX-"
		(at 64.77 107.95 0)
		(effects
			(font
				(size 1.27 1.27)
			)
			(justify left bottom)
		)
	)
	(label "DP0.HPD"
		(at 392.43 41.91 180)
		(effects
			(font
				(size 1.27 1.27)
			)
			(justify right bottom)
		)
	)
	(label "PCIe_{C5x4}.RX1-"
		(at 161.29 189.23 0)
		(effects
			(font
				(size 1.27 1.27)
			)
			(justify left bottom)
		)
	)
	(label "CAM3.CSI7_D1-"
		(at 373.38 212.09 180)
		(effects
			(font
				(size 1.27 1.27)
			)
			(justify right bottom)
		)
	)
	(label "DP1.TX1-"
		(at 265.43 74.93 0)
		(effects
			(font
				(size 1.27 1.27)
			)
			(justify left bottom)
		)
	)
	(label "PCIe_{C5x4}.TX2+"
		(at 161.29 170.18 0)
		(effects
			(font
				(size 1.27 1.27)
			)
			(justify left bottom)
		)
	)
	(label "PCIe_{C5x4}.TX3+"
		(at 138.43 166.37 180)
		(effects
			(font
				(size 1.27 1.27)
			)
			(justify right bottom)
		)
	)
	(label "DP3.TX3-"
		(at 265.43 135.89 0)
		(effects
			(font
				(size 1.27 1.27)
			)
			(justify left bottom)
		)
	)
	(label "PCIe_{C3x2}.TX0+"
		(at 200.66 158.75 0)
		(effects
			(font
				(size 1.27 1.27)
			)
			(justify left bottom)
		)
	)
	(label "PCIe_{C2x1}.~{RST}"
		(at 143.51 71.12 180)
		(effects
			(font
				(size 1.27 1.27)
			)
			(justify right bottom)
		)
	)
	(label "PCIe_{C1x1}.~{CLKREQ}"
		(at 200.66 107.95 0)
		(effects
			(font
				(size 1.27 1.27)
			)
			(justify left bottom)
		)
	)
	(label "CAM1.CSI0_D0+"
		(at 303.53 154.94 0)
		(effects
			(font
				(size 1.27 1.27)
			)
			(justify left bottom)
		)
	)
	(label "PCIe_{C1x1}.CLK-"
		(at 63.5 82.55 0)
		(effects
			(font
				(size 1.27 1.27)
			)
			(justify left bottom)
		)
	)
	(label "TC_JTAG_TCK"
		(at 123.19 241.3 0)
		(effects
			(font
				(size 1.27 1.27)
			)
			(justify left bottom)
		)
	)
	(label "USB0.D-"
		(at 77.47 35.56 180)
		(effects
			(font
				(size 1.27 1.27)
			)
			(justify right bottom)
		)
	)
	(label "TC_JTAG_TRST_N"
		(at 161.29 273.05 180)
		(effects
			(font
				(size 1.27 1.27)
			)
			(justify right bottom)
		)
	)
	(label "PCIe_{C3x2}.TX0-"
		(at 138.43 138.43 180)
		(effects
			(font
				(size 1.27 1.27)
			)
			(justify right bottom)
		)
	)
	(label "USBSS1.RX-"
		(at 64.77 113.03 0)
		(effects
			(font
				(size 1.27 1.27)
			)
			(justify left bottom)
		)
	)
	(label "DP3.TX2_C+"
		(at 295.91 128.27 0)
		(effects
			(font
				(size 1.27 1.27)
			)
			(justify left bottom)
		)
	)
	(label "PCIe_{C5x4}.~{RST}"
		(at 143.51 78.74 180)
		(effects
			(font
				(size 1.27 1.27)
			)
			(justify right bottom)
		)
	)
	(label "PCIe_{C3x2}.RX0+"
		(at 64.77 135.89 0)
		(effects
			(font
				(size 1.27 1.27)
			)
			(justify left bottom)
		)
	)
	(label "DP1.TX0_C+"
		(at 295.91 67.31 0)
		(effects
			(font
				(size 1.27 1.27)
			)
			(justify left bottom)
		)
	)
	(label "DP2.AUX-"
		(at 392.43 110.49 180)
		(effects
			(font
				(size 1.27 1.27)
			)
			(justify right bottom)
		)
	)
	(label "DP1.TX1+"
		(at 265.43 72.39 0)
		(effects
			(font
				(size 1.27 1.27)
			)
			(justify left bottom)
		)
	)
	(label "CAM2.CSI4_D1+"
		(at 373.38 160.02 180)
		(effects
			(font
				(size 1.27 1.27)
			)
			(justify right bottom)
		)
	)
	(label "DP1.AUX_C-"
		(at 350.52 85.09 0)
		(effects
			(font
				(size 1.27 1.27)
			)
			(justify left bottom)
		)
	)
	(label "DP0.TX2_C-"
		(at 295.91 54.61 0)
		(effects
			(font
				(size 1.27 1.27)
			)
			(justify left bottom)
		)
	)
	(label "PCIe_{C5x4}.CLK-"
		(at 63.5 67.31 0)
		(effects
			(font
				(size 1.27 1.27)
			)
			(justify left bottom)
		)
	)
	(label "DP2.TX1-"
		(at 265.43 100.33 0)
		(effects
			(font
				(size 1.27 1.27)
			)
			(justify left bottom)
		)
	)
	(label "PCIe_{C5x4}.~{CLKREQ}"
		(at 161.29 149.86 0)
		(effects
			(font
				(size 1.27 1.27)
			)
			(justify left bottom)
		)
	)
	(label "CAM0.CSI3_D0+"
		(at 303.53 204.47 0)
		(effects
			(font
				(size 1.27 1.27)
			)
			(justify left bottom)
		)
	)
	(label "DP0.TX0_C+"
		(at 295.91 41.91 0)
		(effects
			(font
				(size 1.27 1.27)
			)
			(justify left bottom)
		)
	)
	(label "DP2.TX2+"
		(at 265.43 102.87 0)
		(effects
			(font
				(size 1.27 1.27)
			)
			(justify left bottom)
		)
	)
	(label "DP2.TX2_C-"
		(at 295.91 105.41 0)
		(effects
			(font
				(size 1.27 1.27)
			)
			(justify left bottom)
		)
	)
	(label "PCIe_{C1x1}.TX0+"
		(at 138.43 120.65 180)
		(effects
			(font
				(size 1.27 1.27)
			)
			(justify right bottom)
		)
	)
	(label "PCIe_{C2x1}.TX0-"
		(at 138.43 128.27 180)
		(effects
			(font
				(size 1.27 1.27)
			)
			(justify right bottom)
		)
	)
	(label "PCIe_{C2x1}.~{CLKREQ}"
		(at 143.51 55.88 180)
		(effects
			(font
				(size 1.27 1.27)
			)
			(justify right bottom)
		)
	)
	(label "SFI.TX+"
		(at 200.66 190.5 0)
		(effects
			(font
				(size 1.27 1.27)
			)
			(justify left bottom)
		)
	)
	(label "DP3.TX2_C-"
		(at 295.91 130.81 0)
		(effects
			(font
				(size 1.27 1.27)
			)
			(justify left bottom)
		)
	)
	(label "JTAG_TRST_N"
		(at 97.79 262.89 0)
		(effects
			(font
				(size 1.27 1.27)
			)
			(justify left bottom)
		)
	)
	(label "SFI_REFCLK+"
		(at 290.83 234.95 180)
		(effects
			(font
				(size 1.27 1.27)
			)
			(justify right bottom)
		)
	)
	(label "PCIe_{C2x1}.CLK+"
		(at 161.29 111.76 0)
		(effects
			(font
				(size 1.27 1.27)
			)
			(justify left bottom)
		)
	)
	(label "TC_VCC"
		(at 142.24 255.27 270)
		(effects
			(font
				(size 1.27 1.27)
			)
			(justify right bottom)
		)
	)
	(label "CAM3.CSI6_D1+"
		(at 373.38 193.04 180)
		(effects
			(font
				(size 1.27 1.27)
			)
			(justify right bottom)
		)
	)
	(label "USBSS1.TX+"
		(at 181.61 67.31 0)
		(effects
			(font
				(size 1.27 1.27)
			)
			(justify left bottom)
		)
	)
	(label "USB1.D-"
		(at 77.47 41.91 180)
		(effects
			(font
				(size 1.27 1.27)
			)
			(justify right bottom)
		)
	)
	(label "PCIe_{C5x4}.TX0-"
		(at 161.29 162.56 0)
		(effects
			(font
				(size 1.27 1.27)
			)
			(justify left bottom)
		)
	)
	(label "DP0.TX3_C-"
		(at 295.91 59.69 0)
		(effects
			(font
				(size 1.27 1.27)
			)
			(justify left bottom)
		)
	)
	(label "DP2.TX3_C-"
		(at 295.91 110.49 0)
		(effects
			(font
				(size 1.27 1.27)
			)
			(justify left bottom)
		)
	)
	(label "USBSS0.RX+"
		(at 64.77 105.41 0)
		(effects
			(font
				(size 1.27 1.27)
			)
			(justify left bottom)
		)
	)
	(label "PCIe_{C5x4}.CLK+"
		(at 161.29 153.67 0)
		(effects
			(font
				(size 1.27 1.27)
			)
			(justify left bottom)
		)
	)
	(label "DP2.TX0_C-"
		(at 295.91 95.25 0)
		(effects
			(font
				(size 1.27 1.27)
			)
			(justify left bottom)
		)
	)
	(label "PCIe_{C1x1}.TX0-"
		(at 200.66 120.65 0)
		(effects
			(font
				(size 1.27 1.27)
			)
			(justify left bottom)
		)
	)
	(label "CAM2.CSI4_D1-"
		(at 373.38 162.56 180)
		(effects
			(font
				(size 1.27 1.27)
			)
			(justify right bottom)
		)
	)
	(label "PCIe_{C5x4}.RX1+"
		(at 161.29 186.69 0)
		(effects
			(font
				(size 1.27 1.27)
			)
			(justify left bottom)
		)
	)
	(label "NVDBG_SEL"
		(at 43.18 255.27 0)
		(effects
			(font
				(size 1.27 1.27)
			)
			(justify left bottom)
		)
	)
	(label "CAM1.CSI1_D0-"
		(at 303.53 173.99 0)
		(effects
			(font
				(size 1.27 1.27)
			)
			(justify left bottom)
		)
	)
	(label "DP3.TX0_C+"
		(at 295.91 118.11 0)
		(effects
			(font
				(size 1.27 1.27)
			)
			(justify left bottom)
		)
	)
	(label "DP2.AUX_C-"
		(at 350.52 110.49 0)
		(effects
			(font
				(size 1.27 1.27)
			)
			(justify left bottom)
		)
	)
	(label "PCIe_{C5x4}.CLK+"
		(at 63.5 64.77 0)
		(effects
			(font
				(size 1.27 1.27)
			)
			(justify left bottom)
		)
	)
	(label "DP1.TX0_C-"
		(at 295.91 69.85 0)
		(effects
			(font
				(size 1.27 1.27)
			)
			(justify left bottom)
		)
	)
	(label "DP1.TX1_C-"
		(at 295.91 74.93 0)
		(effects
			(font
				(size 1.27 1.27)
			)
			(justify left bottom)
		)
	)
	(label "PCIe_{C3x2}.CLK-"
		(at 200.66 154.94 0)
		(effects
			(font
				(size 1.27 1.27)
			)
			(justify left bottom)
		)
	)
	(label "CAM2.CSI5_D0-"
		(at 373.38 173.99 180)
		(effects
			(font
				(size 1.27 1.27)
			)
			(justify right bottom)
		)
	)
	(label "PCIe_{C5x4}.RX0-"
		(at 161.29 184.15 0)
		(effects
			(font
				(size 1.27 1.27)
			)
			(justify left bottom)
		)
	)
	(label "USBSS2.TX-"
		(at 138.43 118.11 180)
		(effects
			(font
				(size 1.27 1.27)
			)
			(justify right bottom)
		)
	)
	(label "USBSS0.TX+"
		(at 181.61 52.07 0)
		(effects
			(font
				(size 1.27 1.27)
			)
			(justify left bottom)
		)
	)
	(label "PCIe_{C2x1}.RX0+"
		(at 64.77 125.73 0)
		(effects
			(font
				(size 1.27 1.27)
			)
			(justify left bottom)
		)
	)
	(label "PCIe_{C5x4}.TX2-"
		(at 138.43 163.83 180)
		(effects
			(font
				(size 1.27 1.27)
			)
			(justify right bottom)
		)
	)
	(label "CAM3.CSI6_CLK+"
		(at 373.38 182.88 180)
		(effects
			(font
				(size 1.27 1.27)
			)
			(justify right bottom)
		)
	)
	(label "CAM0.CSI2_D1-"
		(at 303.53 195.58 0)
		(effects
			(font
				(size 1.27 1.27)
			)
			(justify left bottom)
		)
	)
	(label "PCIe_{C5x4}.RX2+"
		(at 64.77 161.29 0)
		(effects
			(font
				(size 1.27 1.27)
			)
			(justify left bottom)
		)
	)
	(label "TC_JTAG_TRST_N"
		(at 184.15 233.68 180)
		(effects
			(font
				(size 1.27 1.27)
			)
			(justify right bottom)
		)
	)
	(label "DP1.TX3_C+"
		(at 295.91 82.55 0)
		(effects
			(font
				(size 1.27 1.27)
			)
			(justify left bottom)
		)
	)
	(label "USBSS1.TX-"
		(at 181.61 69.85 0)
		(effects
			(font
				(size 1.27 1.27)
			)
			(justify left bottom)
		)
	)
	(label "SFI_CLK-"
		(at 252.73 237.49 180)
		(effects
			(font
				(size 1.27 1.27)
			)
			(justify right bottom)
		)
	)
	(label "PCIe_{C5x4}.RX3-"
		(at 161.29 199.39 0)
		(effects
			(font
				(size 1.27 1.27)
			)
			(justify left bottom)
		)
	)
	(label "CAM2.CSI4_D0-"
		(at 373.38 157.48 180)
		(effects
			(font
				(size 1.27 1.27)
			)
			(justify right bottom)
		)
	)
	(label "DP2.AUX+"
		(at 392.43 107.95 180)
		(effects
			(font
				(size 1.27 1.27)
			)
			(justify right bottom)
		)
	)
	(label "CAM0.CSI3_D1+"
		(at 303.53 209.55 0)
		(effects
			(font
				(size 1.27 1.27)
			)
			(justify left bottom)
		)
	)
	(label "DP2.TX0+"
		(at 265.43 92.71 0)
		(effects
			(font
				(size 1.27 1.27)
			)
			(justify left bottom)
		)
	)
	(label "DP1.TX2+"
		(at 265.43 77.47 0)
		(effects
			(font
				(size 1.27 1.27)
			)
			(justify left bottom)
		)
	)
	(label "PCIe_{C2x1}.CLK-"
		(at 161.29 114.3 0)
		(effects
			(font
				(size 1.27 1.27)
			)
			(justify left bottom)
		)
	)
	(label "PCIe_{C3x2}.RX0-"
		(at 64.77 138.43 0)
		(effects
			(font
				(size 1.27 1.27)
			)
			(justify left bottom)
		)
	)
	(hierarchical_label "CAM3{CSI}"
		(shape input)
		(at 381 180.34 0)
		(effects
			(font
				(size 1.27 1.27)
			)
			(justify left)
		)
	)
	(hierarchical_label "USB0{USB}"
		(shape bidirectional)
		(at 64.77 30.48 180)
		(effects
			(font
				(size 1.27 1.27)
			)
			(justify right)
		)
	)
	(hierarchical_label "DP3{DP}"
		(shape output)
		(at 397.51 115.57 0)
		(effects
			(font
				(size 1.27 1.27)
			)
			(justify left)
		)
	)
	(hierarchical_label "CAM0{CSI}"
		(shape input)
		(at 295.91 180.34 180)
		(effects
			(font
				(size 1.27 1.27)
			)
			(justify right)
		)
	)
	(hierarchical_label "USBSS2{USBSS}"
		(shape bidirectional)
		(at 201.93 80.01 0)
		(effects
			(font
				(size 1.27 1.27)
			)
			(justify left)
		)
	)
	(hierarchical_label "CAM1{CSI}"
		(shape input)
		(at 295.91 147.32 180)
		(effects
			(font
				(size 1.27 1.27)
			)
			(justify right)
		)
	)
	(hierarchical_label "PCIe_{C5x4}{PCIe}"
		(shape input)
		(at 181.61 144.78 0)
		(effects
			(font
				(size 1.27 1.27)
			)
			(justify left)
		)
	)
	(hierarchical_label "USB2{USB}"
		(shape bidirectional)
		(at 140.97 30.48 0)
		(effects
			(font
				(size 1.27 1.27)
			)
			(justify left)
		)
	)
	(hierarchical_label "USB1{USB}"
		(shape bidirectional)
		(at 64.77 36.83 180)
		(effects
			(font
				(size 1.27 1.27)
			)
			(justify right)
		)
	)
	(hierarchical_label "DP1{DP}"
		(shape output)
		(at 397.51 64.77 0)
		(effects
			(font
				(size 1.27 1.27)
			)
			(justify left)
		)
	)
	(hierarchical_label "PCIe_{C1x1}{PCIe}"
		(shape input)
		(at 220.98 102.87 0)
		(effects
			(font
				(size 1.27 1.27)
			)
			(justify left)
		)
	)
	(hierarchical_label "~{PEX_WAKE}"
		(shape passive)
		(at 130.81 82.55 0)
		(effects
			(font
				(size 1.27 1.27)
			)
			(justify left)
		)
	)
	(hierarchical_label "DP3{DP}"
		(shape output)
		(at 260.35 115.57 180)
		(effects
			(font
				(size 1.27 1.27)
			)
			(justify right)
		)
	)
	(hierarchical_label "PCIe_{C3x2}{PCIe}"
		(shape bidirectional)
		(at 223.52 143.51 0)
		(effects
			(font
				(size 1.27 1.27)
			)
			(justify left)
		)
	)
	(hierarchical_label "DP2{DP}"
		(shape output)
		(at 397.51 90.17 0)
		(effects
			(font
				(size 1.27 1.27)
			)
			(justify left)
		)
	)
	(hierarchical_label "DP1{DP}"
		(shape output)
		(at 260.35 64.77 180)
		(effects
			(font
				(size 1.27 1.27)
			)
			(justify right)
		)
	)
	(hierarchical_label "CAM2{CSI}"
		(shape input)
		(at 381 147.32 0)
		(effects
			(font
				(size 1.27 1.27)
			)
			(justify left)
		)
	)
	(hierarchical_label "USBSS0{USBSS}"
		(shape bidirectional)
		(at 201.93 49.53 0)
		(effects
			(font
				(size 1.27 1.27)
			)
			(justify left)
		)
	)
	(hierarchical_label "USBSS1{USBSS}"
		(shape bidirectional)
		(at 201.93 64.77 0)
		(effects
			(font
				(size 1.27 1.27)
			)
			(justify left)
		)
	)
	(hierarchical_label "SFI{SFI}"
		(shape bidirectional)
		(at 222.25 187.96 0)
		(effects
			(font
				(size 1.27 1.27)
			)
			(justify left)
		)
	)
	(hierarchical_label "USB3{USB}"
		(shape bidirectional)
		(at 140.97 36.83 0)
		(effects
			(font
				(size 1.27 1.27)
			)
			(justify left)
		)
	)
	(hierarchical_label "DP0{DP}"
		(shape output)
		(at 397.51 39.37 0)
		(effects
			(font
				(size 1.27 1.27)
			)
			(justify left)
		)
	)
	(hierarchical_label "PCIe_{C2x1}{PCIe}"
		(shape bidirectional)
		(at 181.61 102.87 0)
		(effects
			(font
				(size 1.27 1.27)
			)
			(justify left)
		)
	)
	(hierarchical_label "DP2{DP}"
		(shape output)
		(at 260.35 90.17 180)
		(effects
			(font
				(size 1.27 1.27)
			)
			(justify right)
		)
	)
	(hierarchical_label "DP0{DP}"
		(shape output)
		(at 260.35 39.37 180)
		(effects
			(font
				(size 1.27 1.27)
			)
			(justify right)
		)
	)
	(rule_area
		(polyline
			(pts
				(xy 25.4 72.39) (xy 25.4 84.455) (xy 62.23 84.455) (xy 62.23 72.39)
			)
			(stroke
				(width 0)
				(type dash)
			)
			(fill
				(type none)
			)
		)
	)
	(rule_area
		(polyline
			(pts
				(xy 306.07 137.16) (xy 294.64 137.16) (xy 294.64 39.37) (xy 306.07 39.37)
			)
			(stroke
				(width 0)
				(type dash)
			)
			(fill
				(type none)
			)
		)
	)
	(rule_area
		(polyline
			(pts
				(xy 365.76 137.16) (xy 354.33 137.16) (xy 354.33 39.37) (xy 365.76 39.37)
			)
			(stroke
				(width 0)
				(type dash)
			)
			(fill
				(type none)
			)
		)
	)
	(rule_area
		(polyline
			(pts
				(xy 60.96 57.15) (xy 60.96 62.865) (xy 78.105 62.865) (xy 78.105 57.15)
			)
			(stroke
				(width 0)
				(type dash)
			)
			(fill
				(type none)
			)
		)
	)
	(rule_area
		(polyline
			(pts
				(xy 242.57 232.41) (xy 242.57 238.76) (xy 257.81 238.76) (xy 257.81 232.41)
			)
			(stroke
				(width 0)
				(type dash)
			)
			(fill
				(type none)
			)
		)
	)
	(netclass_flag ""
		(length 2.54)
		(shape round)
		(at 294.64 39.37 90)
		(effects
			(font
				(size 1.27 1.27)
			)
			(justify left bottom)
		)
		(property "Netclass" "85Ohm-diff_DP"
			(at 287.02 37.465 0)
			(effects
				(font
					(size 1.27 1.27)
				)
				(justify left)
			)
		)
		(property "Component Class" ""
			(at 252.73 201.93 90)
			(effects
				(font
					(size 1.27 1.27)
					(italic yes)
				)
				(justify right)
			)
		)
	)
	(netclass_flag ""
		(length 2.54)
		(shape round)
		(at 60.96 57.15 0)
		(fields_autoplaced yes)
		(effects
			(font
				(size 1.27 1.27)
			)
			(justify left bottom)
		)
		(property "Netclass" "85Ohm-diff_SFI"
			(at 61.6585 54.61 0)
			(effects
				(font
					(size 1.27 1.27)
				)
				(justify left)
			)
		)
		(property "Component Class" ""
			(at -172.72 -110.49 0)
			(effects
				(font
					(size 1.27 1.27)
					(italic yes)
				)
			)
		)
	)
	(netclass_flag ""
		(length 2.54)
		(shape round)
		(at 257.81 232.41 0)
		(fields_autoplaced yes)
		(effects
			(font
				(size 1.27 1.27)
			)
			(justify left bottom)
		)
		(property "Netclass" "85Ohm-diff_SFI"
			(at 258.5085 229.87 0)
			(effects
				(font
					(size 1.27 1.27)
				)
				(justify left)
			)
		)
		(property "Component Class" ""
			(at 24.13 64.77 0)
			(effects
				(font
					(size 1.27 1.27)
					(italic yes)
				)
			)
		)
	)
	(netclass_flag ""
		(length 2.54)
		(shape round)
		(at 354.33 39.37 90)
		(effects
			(font
				(size 1.27 1.27)
			)
			(justify left bottom)
		)
		(property "Netclass" "85Ohm-diff_DP"
			(at 346.71 37.465 0)
			(effects
				(font
					(size 1.27 1.27)
				)
				(justify left)
			)
		)
		(property "Component Class" ""
			(at 312.42 201.93 90)
			(effects
				(font
					(size 1.27 1.27)
					(italic yes)
				)
				(justify right)
			)
		)
	)
	(netclass_flag ""
		(length 2.54)
		(shape round)
		(at 25.4 72.39 0)
		(fields_autoplaced yes)
		(effects
			(font
				(size 1.27 1.27)
			)
			(justify left bottom)
		)
		(property "Netclass" "85Ohm-diff_PCIE"
			(at 26.0985 69.85 0)
			(effects
				(font
					(size 1.27 1.27)
				)
				(justify left)
			)
		)
		(property "Component Class" ""
			(at -208.28 -95.25 0)
			(effects
				(font
					(size 1.27 1.27)
					(italic yes)
				)
			)
		)
	)
	(symbol
		(lib_id "antmicroCapacitors0402:C_100n_0402")
		(at 279.4 118.11 0)
		(mirror x)
		(unit 1)
		(exclude_from_sim no)
		(in_bom yes)
		(on_board yes)
		(dnp no)
		(property "Reference" "C344"
			(at 288.29 116.84 0)
			(effects
				(font
					(size 1.27 1.27)
				)
				(justify right)
			)
		)
		(property "Value" "C_100n_0402"
			(at 299.72 107.95 0)
			(effects
				(font
					(size 1.27 1.27)
					(thickness 0.15)
				)
				(justify left bottom)
				(hide yes)
			)
		)
		(property "Footprint" "antmicro-footprints:C_0402_1005Metric"
			(at 299.72 105.41 0)
			(effects
				(font
					(size 1.27 1.27)
					(thickness 0.15)
				)
				(justify left bottom)
				(hide yes)
			)
		)
		(property "Datasheet" "https://www.murata.com/products/productdetail?partno=GRM155R61H104KE14%23"
			(at 299.72 102.87 0)
			(effects
				(font
					(size 1.27 1.27)
					(thickness 0.15)
				)
				(justify left bottom)
				(hide yes)
			)
		)
		(property "Description" "SMD Multilayer Ceramic Capacitor, 0.1 µF, 50 V, 0402 [1005 Metric], ± 10%, X5R, GRM Series"
			(at 279.4 118.11 0)
			(effects
				(font
					(size 1.27 1.27)
				)
				(hide yes)
			)
		)
		(property "Manufacturer" "Murata"
			(at 299.72 97.79 0)
			(effects
				(font
					(size 1.27 1.27)
					(thickness 0.15)
				)
				(justify left bottom)
				(hide yes)
			)
		)
		(property "MPN" "GRM155R61H104KE14D"
			(at 299.72 100.33 0)
			(effects
				(font
					(size 1.27 1.27)
					(thickness 0.15)
				)
				(justify left bottom)
				(hide yes)
			)
		)
		(property "Val" "100n"
			(at 280.924 117.094 0)
			(effects
				(font
					(size 1.27 1.27)
					(thickness 0.15)
				)
				(justify right)
			)
		)
		(property "License" "Apache-2.0"
			(at 299.72 95.25 0)
			(effects
				(font
					(size 1.27 1.27)
					(thickness 0.15)
				)
				(justify left bottom)
				(hide yes)
			)
		)
		(property "Author" "Antmicro"
			(at 299.72 92.71 0)
			(effects
				(font
					(size 1.27 1.27)
					(thickness 0.15)
				)
				(justify left bottom)
				(hide yes)
			)
		)
		(property "Voltage" "50V"
			(at 299.72 90.17 0)
			(effects
				(font
					(size 1.27 1.27)
				)
				(justify left bottom)
				(hide yes)
			)
		)
		(property "Dielectric" "X5R"
			(at 299.72 87.63 0)
			(effects
				(font
					(size 1.27 1.27)
				)
				(justify left bottom)
				(hide yes)
			)
		)
		(pin "1"
		)
		(pin "2"
		)
		(instances
			(project "jetson-agx-thor-baseboard"
				(path ""
					(reference "C344")
					(unit 1)
				)
			)
		)
	)
	(symbol
		(lib_id "antmicropower:GND")
		(at 135.89 245.11 0)
		(mirror y)
		(unit 1)
		(exclude_from_sim no)
		(in_bom yes)
		(on_board yes)
		(dnp no)
		(property "Reference" "#PWR0497"
			(at 127 247.65 0)
			(effects
				(font
					(size 1.27 1.27)
					(thickness 0.15)
				)
				(justify left bottom)
				(hide yes)
			)
		)
		(property "Value" "GND"
			(at 135.89 248.92 0)
			(effects
				(font
					(size 1.27 1.27)
					(thickness 0.15)
				)
			)
		)
		(property "Footprint" ""
			(at 127 252.73 0)
			(effects
				(font
					(size 1.27 1.27)
					(thickness 0.15)
				)
				(justify left bottom)
				(hide yes)
			)
		)
		(property "Datasheet" ""
			(at 127 257.81 0)
			(effects
				(font
					(size 1.27 1.27)
					(thickness 0.15)
				)
				(justify left bottom)
				(hide yes)
			)
		)
		(property "Description" ""
			(at 135.89 245.11 0)
			(effects
				(font
					(size 1.27 1.27)
				)
				(hide yes)
			)
		)
		(property "Author" "Antmicro"
			(at 127 252.73 0)
			(effects
				(font
					(size 1.27 1.27)
					(thickness 0.15)
				)
				(justify left bottom)
				(hide yes)
			)
		)
		(property "License" "Apache-2.0"
			(at 127 255.27 0)
			(effects
				(font
					(size 1.27 1.27)
					(thickness 0.15)
				)
				(justify left bottom)
				(hide yes)
			)
		)
		(pin "1"
		)
		(instances
			(project "jetson-agx-thor-baseboard"
				(path ""
					(reference "#PWR0497")
					(unit 1)
				)
			)
		)
	)
	(symbol
		(lib_id "antmicroCapacitors0402:C_100n_0402")
		(at 279.4 41.91 0)
		(mirror x)
		(unit 1)
		(exclude_from_sim no)
		(in_bom yes)
		(on_board yes)
		(dnp no)
		(property "Reference" "C314"
			(at 288.29 40.64 0)
			(effects
				(font
					(size 1.27 1.27)
				)
				(justify right)
			)
		)
		(property "Value" "C_100n_0402"
			(at 299.72 31.75 0)
			(effects
				(font
					(size 1.27 1.27)
					(thickness 0.15)
				)
				(justify left bottom)
				(hide yes)
			)
		)
		(property "Footprint" "antmicro-footprints:C_0402_1005Metric"
			(at 299.72 29.21 0)
			(effects
				(font
					(size 1.27 1.27)
					(thickness 0.15)
				)
				(justify left bottom)
				(hide yes)
			)
		)
		(property "Datasheet" "https://www.murata.com/products/productdetail?partno=GRM155R61H104KE14%23"
			(at 299.72 26.67 0)
			(effects
				(font
					(size 1.27 1.27)
					(thickness 0.15)
				)
				(justify left bottom)
				(hide yes)
			)
		)
		(property "Description" "SMD Multilayer Ceramic Capacitor, 0.1 µF, 50 V, 0402 [1005 Metric], ± 10%, X5R, GRM Series"
			(at 279.4 41.91 0)
			(effects
				(font
					(size 1.27 1.27)
				)
				(hide yes)
			)
		)
		(property "Manufacturer" "Murata"
			(at 299.72 21.59 0)
			(effects
				(font
					(size 1.27 1.27)
					(thickness 0.15)
				)
				(justify left bottom)
				(hide yes)
			)
		)
		(property "MPN" "GRM155R61H104KE14D"
			(at 299.72 24.13 0)
			(effects
				(font
					(size 1.27 1.27)
					(thickness 0.15)
				)
				(justify left bottom)
				(hide yes)
			)
		)
		(property "Val" "100n"
			(at 280.924 40.894 0)
			(effects
				(font
					(size 1.27 1.27)
					(thickness 0.15)
				)
				(justify right)
			)
		)
		(property "License" "Apache-2.0"
			(at 299.72 19.05 0)
			(effects
				(font
					(size 1.27 1.27)
					(thickness 0.15)
				)
				(justify left bottom)
				(hide yes)
			)
		)
		(property "Author" "Antmicro"
			(at 299.72 16.51 0)
			(effects
				(font
					(size 1.27 1.27)
					(thickness 0.15)
				)
				(justify left bottom)
				(hide yes)
			)
		)
		(property "Voltage" "50V"
			(at 299.72 13.97 0)
			(effects
				(font
					(size 1.27 1.27)
				)
				(justify left bottom)
				(hide yes)
			)
		)
		(property "Dielectric" "X5R"
			(at 299.72 11.43 0)
			(effects
				(font
					(size 1.27 1.27)
				)
				(justify left bottom)
				(hide yes)
			)
		)
		(pin "1"
		)
		(pin "2"
		)
		(instances
			(project "jetson-agx-thor-baseboard"
				(path ""
					(reference "C314")
					(unit 1)
				)
			)
		)
	)
	(symbol
		(lib_id "antmicropower:+3V3_AON")
		(at 69.85 252.73 0)
		(mirror y)
		(unit 1)
		(exclude_from_sim no)
		(in_bom yes)
		(on_board yes)
		(dnp no)
		(property "Reference" "#PWR0503"
			(at 69.85 256.54 0)
			(effects
				(font
					(size 1.27 1.27)
				)
				(hide yes)
			)
		)
		(property "Value" "+1V8"
			(at 69.85 248.666 0)
			(effects
				(font
					(size 1.27 1.27)
				)
			)
		)
		(property "Footprint" ""
			(at 69.85 252.73 0)
			(effects
				(font
					(size 1.27 1.27)
				)
				(hide yes)
			)
		)
		(property "Datasheet" ""
			(at 69.85 252.73 0)
			(effects
				(font
					(size 1.27 1.27)
				)
				(hide yes)
			)
		)
		(property "Description" ""
			(at 69.85 252.73 0)
			(effects
				(font
					(size 1.27 1.27)
				)
				(hide yes)
			)
		)
		(pin "1"
		)
		(instances
			(project "jetson-agx-thor-baseboard"
				(path ""
					(reference "#PWR0503")
					(unit 1)
				)
			)
		)
	)
	(symbol
		(lib_id "antmicroCapacitors0402:C_100n_0402")
		(at 66.04 229.87 270)
		(mirror x)
		(unit 1)
		(exclude_from_sim no)
		(in_bom no)
		(on_board yes)
		(dnp yes)
		(property "Reference" "C238"
			(at 63.5 226.0536 90)
			(effects
				(font
					(size 1.27 1.27)
					(thickness 0.15)
				)
				(justify right)
			)
		)
		(property "Value" "C_100n_0402"
			(at 43.18 214.63 0)
			(effects
				(font
					(size 1.27 1.27)
					(thickness 0.15)
				)
				(justify left bottom)
				(hide yes)
			)
		)
		(property "Footprint" "antmicro-footprints:C_0402_1005Metric"
			(at 40.64 214.63 0)
			(effects
				(font
					(size 1.27 1.27)
					(thickness 0.15)
				)
				(justify left bottom)
				(hide yes)
			)
		)
		(property "Datasheet" "https://www.murata.com/products/productdetail?partno=GRM155R61H104KE14%23"
			(at 38.1 214.63 0)
			(effects
				(font
					(size 1.27 1.27)
					(thickness 0.15)
				)
				(justify left bottom)
				(hide yes)
			)
		)
		(property "Description" "SMD Multilayer Ceramic Capacitor, 0.1 µF, 50 V, 0402 [1005 Metric], ± 10%, X5R, GRM Series"
			(at 66.04 229.87 0)
			(effects
				(font
					(size 1.27 1.27)
				)
				(hide yes)
			)
		)
		(property "MPN" "GRM155R61H104KE14D"
			(at 35.56 214.63 0)
			(effects
				(font
					(size 1.27 1.27)
					(thickness 0.15)
				)
				(justify left bottom)
				(hide yes)
			)
		)
		(property "Val" "100n"
			(at 63.5 228.5936 90)
			(effects
				(font
					(size 1.27 1.27)
					(thickness 0.15)
				)
				(justify right)
			)
		)
		(property "Voltage" "50V"
			(at 55.88 214.63 0)
			(effects
				(font
					(size 1.27 1.27)
					(thickness 0.15)
				)
				(justify left bottom)
				(hide yes)
			)
		)
		(property "Dielectric" "X5R"
			(at 53.34 214.63 0)
			(effects
				(font
					(size 1.27 1.27)
					(thickness 0.15)
				)
				(justify left bottom)
				(hide yes)
			)
		)
		(property "Manufacturer" "Murata"
			(at 50.8 214.63 0)
			(effects
				(font
					(size 1.27 1.27)
					(thickness 0.15)
				)
				(justify left bottom)
				(hide yes)
			)
		)
		(property "License" "Apache-2.0"
			(at 48.26 214.63 0)
			(effects
				(font
					(size 1.27 1.27)
					(thickness 0.15)
				)
				(justify left bottom)
				(hide yes)
			)
		)
		(property "Author" "Antmicro"
			(at 45.72 214.63 0)
			(effects
				(font
					(size 1.27 1.27)
					(thickness 0.15)
				)
				(justify left bottom)
				(hide yes)
			)
		)
		(pin "2"
		)
		(pin "1"
		)
		(instances
			(project "jetson-agx-thor-baseboard"
				(path ""
					(reference "C238")
					(unit 1)
				)
			)
		)
	)
	(symbol
		(lib_id "antmicropower:+3V3_AON")
		(at 66.04 222.25 0)
		(mirror y)
		(unit 1)
		(exclude_from_sim no)
		(in_bom yes)
		(on_board yes)
		(dnp no)
		(property "Reference" "#PWR0504"
			(at 66.04 226.06 0)
			(effects
				(font
					(size 1.27 1.27)
				)
				(hide yes)
			)
		)
		(property "Value" "+1V8"
			(at 63.246 217.932 0)
			(effects
				(font
					(size 1.27 1.27)
				)
				(justify right)
			)
		)
		(property "Footprint" ""
			(at 66.04 222.25 0)
			(effects
				(font
					(size 1.27 1.27)
				)
				(hide yes)
			)
		)
		(property "Datasheet" ""
			(at 66.04 222.25 0)
			(effects
				(font
					(size 1.27 1.27)
				)
				(hide yes)
			)
		)
		(property "Description" ""
			(at 66.04 222.25 0)
			(effects
				(font
					(size 1.27 1.27)
				)
				(hide yes)
			)
		)
		(pin "1"
		)
		(instances
			(project "jetson-agx-thor-baseboard"
				(path ""
					(reference "#PWR0504")
					(unit 1)
				)
			)
		)
	)
	(symbol
		(lib_id "antmicroCapacitors0402:C_100n_0402")
		(at 279.4 57.15 0)
		(mirror x)
		(unit 1)
		(exclude_from_sim no)
		(in_bom yes)
		(on_board yes)
		(dnp no)
		(property "Reference" "C320"
			(at 288.29 55.88 0)
			(effects
				(font
					(size 1.27 1.27)
				)
				(justify right)
			)
		)
		(property "Value" "C_100n_0402"
			(at 299.72 46.99 0)
			(effects
				(font
					(size 1.27 1.27)
					(thickness 0.15)
				)
				(justify left bottom)
				(hide yes)
			)
		)
		(property "Footprint" "antmicro-footprints:C_0402_1005Metric"
			(at 299.72 44.45 0)
			(effects
				(font
					(size 1.27 1.27)
					(thickness 0.15)
				)
				(justify left bottom)
				(hide yes)
			)
		)
		(property "Datasheet" "https://www.murata.com/products/productdetail?partno=GRM155R61H104KE14%23"
			(at 299.72 41.91 0)
			(effects
				(font
					(size 1.27 1.27)
					(thickness 0.15)
				)
				(justify left bottom)
				(hide yes)
			)
		)
		(property "Description" "SMD Multilayer Ceramic Capacitor, 0.1 µF, 50 V, 0402 [1005 Metric], ± 10%, X5R, GRM Series"
			(at 279.4 57.15 0)
			(effects
				(font
					(size 1.27 1.27)
				)
				(hide yes)
			)
		)
		(property "Manufacturer" "Murata"
			(at 299.72 36.83 0)
			(effects
				(font
					(size 1.27 1.27)
					(thickness 0.15)
				)
				(justify left bottom)
				(hide yes)
			)
		)
		(property "MPN" "GRM155R61H104KE14D"
			(at 299.72 39.37 0)
			(effects
				(font
					(size 1.27 1.27)
					(thickness 0.15)
				)
				(justify left bottom)
				(hide yes)
			)
		)
		(property "Val" "100n"
			(at 280.924 56.134 0)
			(effects
				(font
					(size 1.27 1.27)
					(thickness 0.15)
				)
				(justify right)
			)
		)
		(property "License" "Apache-2.0"
			(at 299.72 34.29 0)
			(effects
				(font
					(size 1.27 1.27)
					(thickness 0.15)
				)
				(justify left bottom)
				(hide yes)
			)
		)
		(property "Author" "Antmicro"
			(at 299.72 31.75 0)
			(effects
				(font
					(size 1.27 1.27)
					(thickness 0.15)
				)
				(justify left bottom)
				(hide yes)
			)
		)
		(property "Voltage" "50V"
			(at 299.72 29.21 0)
			(effects
				(font
					(size 1.27 1.27)
				)
				(justify left bottom)
				(hide yes)
			)
		)
		(property "Dielectric" "X5R"
			(at 299.72 26.67 0)
			(effects
				(font
					(size 1.27 1.27)
				)
				(justify left bottom)
				(hide yes)
			)
		)
		(pin "1"
		)
		(pin "2"
		)
		(instances
			(project "jetson-agx-thor-baseboard"
				(path ""
					(reference "C320")
					(unit 1)
				)
			)
		)
	)
	(symbol
		(lib_id "antmicroResistors0402:R_33R_0402")
		(at 257.81 237.49 0)
		(unit 1)
		(exclude_from_sim no)
		(in_bom yes)
		(on_board yes)
		(dnp no)
		(property "Reference" "R3"
			(at 255.27 236.22 0)
			(effects
				(font
					(size 1.27 1.27)
					(thickness 0.15)
				)
			)
		)
		(property "Value" "R_33R_0402"
			(at 278.13 250.19 0)
			(effects
				(font
					(size 1.27 1.27)
					(thickness 0.15)
				)
				(justify left bottom)
				(hide yes)
			)
		)
		(property "Footprint" "antmicro-footprints:R_0402_1005Metric"
			(at 278.13 252.73 0)
			(effects
				(font
					(size 1.27 1.27)
					(thickness 0.15)
				)
				(justify left bottom)
				(hide yes)
			)
		)
		(property "Datasheet" "https://www.bourns.com/docs/product-datasheets/cr.pdf"
			(at 278.13 255.27 0)
			(effects
				(font
					(size 1.27 1.27)
					(thickness 0.15)
				)
				(justify left bottom)
				(hide yes)
			)
		)
		(property "Description" "SMD Chip Resistor, 33 ohm, ± 1%, 62.5 mW, 0402 [1005 Metric], Thick Film, General Purpose"
			(at 257.81 237.49 0)
			(effects
				(font
					(size 1.27 1.27)
				)
				(hide yes)
			)
		)
		(property "MPN" "CR0402-FX-33R0GLF"
			(at 278.13 257.81 0)
			(effects
				(font
					(size 1.27 1.27)
					(thickness 0.15)
				)
				(justify left bottom)
				(hide yes)
			)
		)
		(property "Manufacturer" "Bourns"
			(at 278.13 260.35 0)
			(effects
				(font
					(size 1.27 1.27)
					(thickness 0.15)
				)
				(justify left bottom)
				(hide yes)
			)
		)
		(property "License" "Apache-2.0"
			(at 278.13 262.89 0)
			(effects
				(font
					(size 1.27 1.27)
					(thickness 0.15)
				)
				(justify left bottom)
				(hide yes)
			)
		)
		(property "Author" "Antmicro"
			(at 278.13 265.43 0)
			(effects
				(font
					(size 1.27 1.27)
					(thickness 0.15)
				)
				(justify left bottom)
				(hide yes)
			)
		)
		(property "Val" "33R"
			(at 264.795 236.22 0)
			(effects
				(font
					(size 1.27 1.27)
					(thickness 0.15)
				)
			)
		)
		(property "Tolerance" "1%"
			(at 278.13 247.65 0)
			(effects
				(font
					(size 1.27 1.27)
				)
				(justify left bottom)
				(hide yes)
			)
		)
		(pin "2"
		)
		(pin "1"
		)
		(instances
			(project "jetson-agx-thor-baseboard"
				(path ""
					(reference "R3")
					(unit 1)
				)
			)
		)
	)
	(symbol
		(lib_id "antmicroResistors0402:R_0R_0402")
		(at 46.99 74.93 0)
		(unit 1)
		(exclude_from_sim no)
		(in_bom no)
		(on_board yes)
		(dnp yes)
		(property "Reference" "R196"
			(at 43.942 73.66 0)
			(effects
				(font
					(size 1.27 1.27)
					(thickness 0.15)
				)
			)
		)
		(property "Value" "R_0R_0402"
			(at 67.31 87.63 0)
			(effects
				(font
					(size 1.27 1.27)
					(thickness 0.15)
				)
				(justify left bottom)
				(hide yes)
			)
		)
		(property "Footprint" "antmicro-footprints:R_0402_1005Metric"
			(at 67.31 90.17 0)
			(effects
				(font
					(size 1.27 1.27)
					(thickness 0.15)
				)
				(justify left bottom)
				(hide yes)
			)
		)
		(property "Datasheet" "https://industrial.panasonic.com/cdbs/www-data/pdf/RDA0000/AOA0000C301.pdf"
			(at 67.31 92.71 0)
			(effects
				(font
					(size 1.27 1.27)
					(thickness 0.15)
				)
				(justify left bottom)
				(hide yes)
			)
		)
		(property "Description" "SMD Chip Resistor, Jumper, 0 ohm, 100 mW, 0402 [1005 Metric], Thick Film, General Purpose"
			(at 46.99 74.93 0)
			(effects
				(font
					(size 1.27 1.27)
				)
				(hide yes)
			)
		)
		(property "MPN" "ERJ2GE0R00X"
			(at 67.31 95.25 0)
			(effects
				(font
					(size 1.27 1.27)
					(thickness 0.15)
				)
				(justify left bottom)
				(hide yes)
			)
		)
		(property "Manufacturer" "Panasonic"
			(at 67.31 97.79 0)
			(effects
				(font
					(size 1.27 1.27)
					(thickness 0.15)
				)
				(justify left bottom)
				(hide yes)
			)
		)
		(property "License" "Apache-2.0"
			(at 67.31 100.33 0)
			(effects
				(font
					(size 1.27 1.27)
					(thickness 0.15)
				)
				(justify left bottom)
				(hide yes)
			)
		)
		(property "Author" "Antmicro"
			(at 67.31 102.87 0)
			(effects
				(font
					(size 1.27 1.27)
					(thickness 0.15)
				)
				(justify left bottom)
				(hide yes)
			)
		)
		(property "Val" "0R"
			(at 53.34 73.66 0)
			(effects
				(font
					(size 1.27 1.27)
					(thickness 0.15)
				)
			)
		)
		(property "Tolerance" "~"
			(at 67.31 85.09 0)
			(effects
				(font
					(size 1.27 1.27)
				)
				(justify left bottom)
				(hide yes)
			)
		)
		(property "Current" "1A"
			(at 67.31 105.41 0)
			(effects
				(font
					(size 1.27 1.27)
					(thickness 0.15)
				)
				(justify left bottom)
				(hide yes)
			)
		)
		(pin "1"
		)
		(pin "2"
		)
		(instances
			(project "jetson-agx-thor-baseboard"
				(path ""
					(reference "R196")
					(unit 1)
				)
			)
		)
	)
	(symbol
		(lib_id "antmicroOscillators:Oscillator_100MHz_NX324")
		(at 223.52 262.89 0)
		(unit 1)
		(exclude_from_sim no)
		(in_bom yes)
		(on_board yes)
		(dnp no)
		(fields_autoplaced yes)
		(property "Reference" "Y1"
			(at 233.045 252.73 0)
			(effects
				(font
					(size 1.27 1.27)
					(thickness 0.15)
				)
			)
		)
		(property "Value" "Oscillator_100MHz_NX324"
			(at 252.73 274.955 0)
			(effects
				(font
					(size 1.27 1.27)
					(thickness 0.15)
				)
				(justify left bottom)
				(hide yes)
			)
		)
		(property "Footprint" "antmicro-footprints:Oscillator_SMD_Abracon_AX3_3.2x2.5x1mm"
			(at 252.73 277.495 0)
			(effects
				(font
					(size 1.27 1.27)
					(thickness 0.15)
				)
				(justify left bottom)
				(hide yes)
			)
		)
		(property "Datasheet" "https://www.diodes.com/assets/Datasheets/NX324.pdf"
			(at 252.73 280.035 0)
			(effects
				(font
					(size 1.27 1.27)
					(thickness 0.15)
				)
				(justify left bottom)
				(hide yes)
			)
		)
		(property "Description" "100 MHz XO (Standard) HCSL Oscillator 3.3V Enable/Disable 6-SMD, No Lead"
			(at 252.73 287.655 0)
			(effects
				(font
					(size 1.27 1.27)
				)
				(justify left bottom)
				(hide yes)
			)
		)
		(property "Manufacturer" "Diodes Incorporated"
			(at 252.73 267.335 0)
			(effects
				(font
					(size 1.27 1.27)
					(thickness 0.15)
				)
				(justify left bottom)
				(hide yes)
			)
		)
		(property "MPN" "NX3241E0100.000000"
			(at 233.045 255.27 0)
			(effects
				(font
					(size 1.27 1.27)
					(thickness 0.15)
				)
			)
		)
		(property "Val" "100 MHz"
			(at 233.045 257.81 0)
			(effects
				(font
					(size 1.27 1.27)
					(thickness 0.15)
				)
			)
		)
		(property "Author" "Antmicro"
			(at 252.73 282.575 0)
			(effects
				(font
					(size 1.27 1.27)
					(thickness 0.15)
				)
				(justify left bottom)
				(hide yes)
			)
		)
		(property "License" "Apache-2.0"
			(at 252.73 285.115 0)
			(effects
				(font
					(size 1.27 1.27)
					(thickness 0.15)
				)
				(justify left bottom)
				(hide yes)
			)
		)
		(pin "3"
		)
		(pin "4"
		)
		(pin "6"
		)
		(pin "5"
		)
		(pin "1"
		)
		(pin "2"
		)
		(instances
			(project ""
				(path ""
					(reference "Y1")
					(unit 1)
				)
			)
		)
	)
	(symbol
		(lib_id "antmicroResistors0402:R_0R_0402")
		(at 62.23 255.27 0)
		(mirror y)
		(unit 1)
		(exclude_from_sim no)
		(in_bom no)
		(on_board yes)
		(dnp yes)
		(property "Reference" "R291"
			(at 64.77 254 0)
			(effects
				(font
					(size 1.27 1.27)
					(thickness 0.15)
				)
			)
		)
		(property "Value" "R_0R_0402"
			(at 41.91 267.97 0)
			(effects
				(font
					(size 1.27 1.27)
					(thickness 0.15)
				)
				(justify left bottom)
				(hide yes)
			)
		)
		(property "Footprint" "antmicro-footprints:R_0402_1005Metric"
			(at 41.91 270.51 0)
			(effects
				(font
					(size 1.27 1.27)
					(thickness 0.15)
				)
				(justify left bottom)
				(hide yes)
			)
		)
		(property "Datasheet" "https://industrial.panasonic.com/cdbs/www-data/pdf/RDA0000/AOA0000C301.pdf"
			(at 41.91 273.05 0)
			(effects
				(font
					(size 1.27 1.27)
					(thickness 0.15)
				)
				(justify left bottom)
				(hide yes)
			)
		)
		(property "Description" "SMD Chip Resistor, Jumper, 0 ohm, 100 mW, 0402 [1005 Metric], Thick Film, General Purpose"
			(at 62.23 255.27 0)
			(effects
				(font
					(size 1.27 1.27)
				)
				(hide yes)
			)
		)
		(property "MPN" "ERJ2GE0R00X"
			(at 41.91 275.59 0)
			(effects
				(font
					(size 1.27 1.27)
					(thickness 0.15)
				)
				(justify left bottom)
				(hide yes)
			)
		)
		(property "Manufacturer" "Panasonic"
			(at 41.91 278.13 0)
			(effects
				(font
					(size 1.27 1.27)
					(thickness 0.15)
				)
				(justify left bottom)
				(hide yes)
			)
		)
		(property "License" "Apache-2.0"
			(at 41.91 280.67 0)
			(effects
				(font
					(size 1.27 1.27)
					(thickness 0.15)
				)
				(justify left bottom)
				(hide yes)
			)
		)
		(property "Author" "Antmicro"
			(at 41.91 283.21 0)
			(effects
				(font
					(size 1.27 1.27)
					(thickness 0.15)
				)
				(justify left bottom)
				(hide yes)
			)
		)
		(property "Val" "0R"
			(at 55.88 254 0)
			(effects
				(font
					(size 1.27 1.27)
					(thickness 0.15)
				)
			)
		)
		(property "Tolerance" "~"
			(at 41.91 265.43 0)
			(effects
				(font
					(size 1.27 1.27)
				)
				(justify left bottom)
				(hide yes)
			)
		)
		(property "Current" "1A"
			(at 41.91 285.75 0)
			(effects
				(font
					(size 1.27 1.27)
					(thickness 0.15)
				)
				(justify left bottom)
				(hide yes)
			)
		)
		(pin "2"
		)
		(pin "1"
		)
		(instances
			(project "jetson-agx-thor-baseboard"
				(path ""
					(reference "R291")
					(unit 1)
				)
			)
		)
	)
	(symbol
		(lib_id "antmicroResistors0402:R_0R_0402")
		(at 62.23 252.73 0)
		(mirror y)
		(unit 1)
		(exclude_from_sim no)
		(in_bom no)
		(on_board yes)
		(dnp yes)
		(property "Reference" "R290"
			(at 64.77 251.46 0)
			(effects
				(font
					(size 1.27 1.27)
					(thickness 0.15)
				)
			)
		)
		(property "Value" "R_0R_0402"
			(at 41.91 265.43 0)
			(effects
				(font
					(size 1.27 1.27)
					(thickness 0.15)
				)
				(justify left bottom)
				(hide yes)
			)
		)
		(property "Footprint" "antmicro-footprints:R_0402_1005Metric"
			(at 41.91 267.97 0)
			(effects
				(font
					(size 1.27 1.27)
					(thickness 0.15)
				)
				(justify left bottom)
				(hide yes)
			)
		)
		(property "Datasheet" "https://industrial.panasonic.com/cdbs/www-data/pdf/RDA0000/AOA0000C301.pdf"
			(at 41.91 270.51 0)
			(effects
				(font
					(size 1.27 1.27)
					(thickness 0.15)
				)
				(justify left bottom)
				(hide yes)
			)
		)
		(property "Description" "SMD Chip Resistor, Jumper, 0 ohm, 100 mW, 0402 [1005 Metric], Thick Film, General Purpose"
			(at 62.23 252.73 0)
			(effects
				(font
					(size 1.27 1.27)
				)
				(hide yes)
			)
		)
		(property "MPN" "ERJ2GE0R00X"
			(at 41.91 273.05 0)
			(effects
				(font
					(size 1.27 1.27)
					(thickness 0.15)
				)
				(justify left bottom)
				(hide yes)
			)
		)
		(property "Manufacturer" "Panasonic"
			(at 41.91 275.59 0)
			(effects
				(font
					(size 1.27 1.27)
					(thickness 0.15)
				)
				(justify left bottom)
				(hide yes)
			)
		)
		(property "License" "Apache-2.0"
			(at 41.91 278.13 0)
			(effects
				(font
					(size 1.27 1.27)
					(thickness 0.15)
				)
				(justify left bottom)
				(hide yes)
			)
		)
		(property "Author" "Antmicro"
			(at 41.91 280.67 0)
			(effects
				(font
					(size 1.27 1.27)
					(thickness 0.15)
				)
				(justify left bottom)
				(hide yes)
			)
		)
		(property "Val" "0R"
			(at 55.88 251.46 0)
			(effects
				(font
					(size 1.27 1.27)
					(thickness 0.15)
				)
			)
		)
		(property "Tolerance" "~"
			(at 41.91 262.89 0)
			(effects
				(font
					(size 1.27 1.27)
				)
				(justify left bottom)
				(hide yes)
			)
		)
		(property "Current" "1A"
			(at 41.91 283.21 0)
			(effects
				(font
					(size 1.27 1.27)
					(thickness 0.15)
				)
				(justify left bottom)
				(hide yes)
			)
		)
		(pin "2"
		)
		(pin "1"
		)
		(instances
			(project "jetson-agx-thor-baseboard"
				(path ""
					(reference "R290")
					(unit 1)
				)
			)
		)
	)
	(symbol
		(lib_id "antmicroResistors0402:R_0R_0402")
		(at 46.99 80.01 0)
		(unit 1)
		(exclude_from_sim no)
		(in_bom yes)
		(on_board yes)
		(dnp no)
		(property "Reference" "R201"
			(at 43.942 78.74 0)
			(effects
				(font
					(size 1.27 1.27)
					(thickness 0.15)
				)
			)
		)
		(property "Value" "R_0R_0402"
			(at 67.31 92.71 0)
			(effects
				(font
					(size 1.27 1.27)
					(thickness 0.15)
				)
				(justify left bottom)
				(hide yes)
			)
		)
		(property "Footprint" "antmicro-footprints:R_0402_1005Metric"
			(at 67.31 95.25 0)
			(effects
				(font
					(size 1.27 1.27)
					(thickness 0.15)
				)
				(justify left bottom)
				(hide yes)
			)
		)
		(property "Datasheet" "https://industrial.panasonic.com/cdbs/www-data/pdf/RDA0000/AOA0000C301.pdf"
			(at 67.31 97.79 0)
			(effects
				(font
					(size 1.27 1.27)
					(thickness 0.15)
				)
				(justify left bottom)
				(hide yes)
			)
		)
		(property "Description" "SMD Chip Resistor, Jumper, 0 ohm, 100 mW, 0402 [1005 Metric], Thick Film, General Purpose"
			(at 46.99 80.01 0)
			(effects
				(font
					(size 1.27 1.27)
				)
				(hide yes)
			)
		)
		(property "MPN" "ERJ2GE0R00X"
			(at 67.31 100.33 0)
			(effects
				(font
					(size 1.27 1.27)
					(thickness 0.15)
				)
				(justify left bottom)
				(hide yes)
			)
		)
		(property "Manufacturer" "Panasonic"
			(at 67.31 102.87 0)
			(effects
				(font
					(size 1.27 1.27)
					(thickness 0.15)
				)
				(justify left bottom)
				(hide yes)
			)
		)
		(property "License" "Apache-2.0"
			(at 67.31 105.41 0)
			(effects
				(font
					(size 1.27 1.27)
					(thickness 0.15)
				)
				(justify left bottom)
				(hide yes)
			)
		)
		(property "Author" "Antmicro"
			(at 67.31 107.95 0)
			(effects
				(font
					(size 1.27 1.27)
					(thickness 0.15)
				)
				(justify left bottom)
				(hide yes)
			)
		)
		(property "Val" "0R"
			(at 53.34 78.74 0)
			(effects
				(font
					(size 1.27 1.27)
					(thickness 0.15)
				)
			)
		)
		(property "Tolerance" "~"
			(at 67.31 90.17 0)
			(effects
				(font
					(size 1.27 1.27)
				)
				(justify left bottom)
				(hide yes)
			)
		)
		(property "Current" "1A"
			(at 67.31 110.49 0)
			(effects
				(font
					(size 1.27 1.27)
					(thickness 0.15)
				)
				(justify left bottom)
				(hide yes)
			)
		)
		(pin "1"
		)
		(pin "2"
		)
		(instances
			(project "jetson-agx-thor-baseboard"
				(path ""
					(reference "R201")
					(unit 1)
				)
			)
		)
	)
	(symbol
		(lib_id "antmicroTransistorsFETsMOSFETsSingle:DMG1012T-7")
		(at 137.16 273.05 0)
		(mirror y)
		(unit 1)
		(exclude_from_sim no)
		(in_bom no)
		(on_board yes)
		(dnp yes)
		(property "Reference" "Q36"
			(at 137.414 276.606 0)
			(effects
				(font
					(size 1.27 1.27)
					(thickness 0.15)
				)
				(justify left)
			)
		)
		(property "Value" "DMG1012T-7"
			(at 114.3 281.94 0)
			(effects
				(font
					(size 1.27 1.27)
					(thickness 0.15)
				)
				(justify left bottom)
				(hide yes)
			)
		)
		(property "Footprint" "antmicro-footprints:SOT-523"
			(at 114.3 284.48 0)
			(effects
				(font
					(size 1.27 1.27)
					(thickness 0.15)
				)
				(justify left bottom)
				(hide yes)
			)
		)
		(property "Datasheet" "https://www.diodes.com/assets/Datasheets/ds31783.pdf"
			(at 114.3 287.02 0)
			(effects
				(font
					(size 1.27 1.27)
					(thickness 0.15)
				)
				(justify left bottom)
				(hide yes)
			)
		)
		(property "Description" "Power MOSFET, N Channel, 20 V, 630 mA, 0.3 ohm, SOT-523, Surface Mount"
			(at 114.3 298.704 0)
			(effects
				(font
					(size 1.27 1.27)
				)
				(justify left)
				(hide yes)
			)
		)
		(property "MPN" "DMG1012T-7"
			(at 146.05 278.638 0)
			(effects
				(font
					(size 1.27 1.27)
					(thickness 0.15)
				)
				(justify left)
			)
		)
		(property "Manufacturer" "Diodes Incorporated"
			(at 114.3 292.1 0)
			(effects
				(font
					(size 1.27 1.27)
					(thickness 0.15)
				)
				(justify left bottom)
				(hide yes)
			)
		)
		(property "Author" "Antmicro"
			(at 114.3 294.64 0)
			(effects
				(font
					(size 1.27 1.27)
					(thickness 0.15)
				)
				(justify left bottom)
				(hide yes)
			)
		)
		(property "License" "Apache-2.0"
			(at 114.3 297.18 0)
			(effects
				(font
					(size 1.27 1.27)
					(thickness 0.15)
				)
				(justify left bottom)
				(hide yes)
			)
		)
		(pin "2"
		)
		(pin "1"
		)
		(pin "3"
		)
		(instances
			(project "jetson-agx-thor-baseboard"
				(path ""
					(reference "Q36")
					(unit 1)
				)
			)
		)
	)
	(symbol
		(lib_id "antmicroResistors0402:R_49R9_0402")
		(at 266.7 245.11 90)
		(unit 1)
		(exclude_from_sim no)
		(in_bom yes)
		(on_board yes)
		(dnp no)
		(property "Reference" "R4"
			(at 267.97 241.3 90)
			(effects
				(font
					(size 1.27 1.27)
					(thickness 0.15)
				)
				(justify right)
			)
		)
		(property "Value" "R_49R9_0402"
			(at 279.4 224.79 0)
			(effects
				(font
					(size 1.27 1.27)
					(thickness 0.15)
				)
				(justify left bottom)
				(hide yes)
			)
		)
		(property "Footprint" "antmicro-footprints:R_0402_1005Metric"
			(at 281.94 224.79 0)
			(effects
				(font
					(size 1.27 1.27)
					(thickness 0.15)
				)
				(justify left bottom)
				(hide yes)
			)
		)
		(property "Datasheet" "https://www.bourns.com/docs/product-datasheets/cr.pdf"
			(at 284.48 224.79 0)
			(effects
				(font
					(size 1.27 1.27)
					(thickness 0.15)
				)
				(justify left bottom)
				(hide yes)
			)
		)
		(property "Description" "SMD Chip Resistor, 49.9 ohm, ± 1%, 62.5 mW, 0402 [1005 Metric], Thick Film, General Purpose"
			(at 266.7 245.11 0)
			(effects
				(font
					(size 1.27 1.27)
				)
				(hide yes)
			)
		)
		(property "MPN" "CR0402-FX-49R9GLF"
			(at 287.02 224.79 0)
			(effects
				(font
					(size 1.27 1.27)
					(thickness 0.15)
				)
				(justify left bottom)
				(hide yes)
			)
		)
		(property "Manufacturer" "Bourns"
			(at 289.56 224.79 0)
			(effects
				(font
					(size 1.27 1.27)
					(thickness 0.15)
				)
				(justify left bottom)
				(hide yes)
			)
		)
		(property "License" "Apache-2.0"
			(at 292.1 224.79 0)
			(effects
				(font
					(size 1.27 1.27)
					(thickness 0.15)
				)
				(justify left bottom)
				(hide yes)
			)
		)
		(property "Author" "Antmicro"
			(at 294.64 224.79 0)
			(effects
				(font
					(size 1.27 1.27)
					(thickness 0.15)
				)
				(justify left bottom)
				(hide yes)
			)
		)
		(property "Val" "49R9"
			(at 267.97 243.84 90)
			(effects
				(font
					(size 1.27 1.27)
					(thickness 0.15)
				)
				(justify right)
			)
		)
		(property "Tolerance" "1%"
			(at 276.86 224.79 0)
			(effects
				(font
					(size 1.27 1.27)
				)
				(justify left bottom)
				(hide yes)
			)
		)
		(pin "1"
		)
		(pin "2"
		)
		(instances
			(project "jetson-agx-thor-baseboard"
				(path ""
					(reference "R4")
					(unit 1)
				)
			)
		)
	)
	(symbol
		(lib_id "antmicroResistors0402:R_0R_0402")
		(at 115.57 231.14 90)
		(unit 1)
		(exclude_from_sim no)
		(in_bom no)
		(on_board yes)
		(dnp yes)
		(fields_autoplaced yes)
		(property "Reference" "R341"
			(at 118.11 227.33 90)
			(effects
				(font
					(size 1.27 1.27)
					(thickness 0.15)
				)
				(justify right)
			)
		)
		(property "Value" "R_0R_0402"
			(at 128.27 210.82 0)
			(effects
				(font
					(size 1.27 1.27)
					(thickness 0.15)
				)
				(justify left bottom)
				(hide yes)
			)
		)
		(property "Footprint" "antmicro-footprints:R_0402_1005Metric"
			(at 130.81 210.82 0)
			(effects
				(font
					(size 1.27 1.27)
					(thickness 0.15)
				)
				(justify left bottom)
				(hide yes)
			)
		)
		(property "Datasheet" "https://industrial.panasonic.com/cdbs/www-data/pdf/RDA0000/AOA0000C301.pdf"
			(at 133.35 210.82 0)
			(effects
				(font
					(size 1.27 1.27)
					(thickness 0.15)
				)
				(justify left bottom)
				(hide yes)
			)
		)
		(property "Description" "SMD Chip Resistor, Jumper, 0 ohm, 100 mW, 0402 [1005 Metric], Thick Film, General Purpose"
			(at 148.59 210.82 0)
			(effects
				(font
					(size 1.27 1.27)
				)
				(justify left bottom)
				(hide yes)
			)
		)
		(property "MPN" "ERJ2GE0R00X"
			(at 135.89 210.82 0)
			(effects
				(font
					(size 1.27 1.27)
					(thickness 0.15)
				)
				(justify left bottom)
				(hide yes)
			)
		)
		(property "Manufacturer" "Panasonic"
			(at 138.43 210.82 0)
			(effects
				(font
					(size 1.27 1.27)
					(thickness 0.15)
				)
				(justify left bottom)
				(hide yes)
			)
		)
		(property "License" "Apache-2.0"
			(at 140.97 210.82 0)
			(effects
				(font
					(size 1.27 1.27)
					(thickness 0.15)
				)
				(justify left bottom)
				(hide yes)
			)
		)
		(property "Author" "Antmicro"
			(at 143.51 210.82 0)
			(effects
				(font
					(size 1.27 1.27)
					(thickness 0.15)
				)
				(justify left bottom)
				(hide yes)
			)
		)
		(property "Val" "0R"
			(at 118.11 229.87 90)
			(effects
				(font
					(size 1.27 1.27)
					(thickness 0.15)
				)
				(justify right)
			)
		)
		(property "Tolerance" "~"
			(at 125.73 210.82 0)
			(effects
				(font
					(size 1.27 1.27)
				)
				(justify left bottom)
				(hide yes)
			)
		)
		(property "Current" "1A"
			(at 146.05 210.82 0)
			(effects
				(font
					(size 1.27 1.27)
					(thickness 0.15)
				)
				(justify left bottom)
				(hide yes)
			)
		)
		(pin "2"
		)
		(pin "1"
		)
		(instances
			(project ""
				(path ""
					(reference "R341")
					(unit 1)
				)
			)
		)
	)
	(symbol
		(lib_id "antmicroResistors0402:R_10k_0402")
		(at 130.81 261.62 270)
		(mirror x)
		(unit 1)
		(exclude_from_sim no)
		(in_bom no)
		(on_board yes)
		(dnp yes)
		(fields_autoplaced yes)
		(property "Reference" "R126"
			(at 133.35 257.81 90)
			(effects
				(font
					(size 1.27 1.27)
					(thickness 0.15)
				)
				(justify left)
			)
		)
		(property "Value" "R_10k_0402"
			(at 118.11 241.3 0)
			(effects
				(font
					(size 1.27 1.27)
					(thickness 0.15)
				)
				(justify left bottom)
				(hide yes)
			)
		)
		(property "Footprint" "antmicro-footprints:R_0402_1005Metric"
			(at 115.57 241.3 0)
			(effects
				(font
					(size 1.27 1.27)
					(thickness 0.15)
				)
				(justify left bottom)
				(hide yes)
			)
		)
		(property "Datasheet" "https://www.bourns.com/docs/product-datasheets/cr.pdf"
			(at 113.03 241.3 0)
			(effects
				(font
					(size 1.27 1.27)
					(thickness 0.15)
				)
				(justify left bottom)
				(hide yes)
			)
		)
		(property "Description" "SMD Chip Resistor, 10 kohm, ± 1%, 62.5 mW, 0402 [1005 Metric], Thick Film, General Purpose"
			(at 130.81 261.62 0)
			(effects
				(font
					(size 1.27 1.27)
				)
				(hide yes)
			)
		)
		(property "MPN" "CR0402-FX-1002GLF"
			(at 110.49 241.3 0)
			(effects
				(font
					(size 1.27 1.27)
					(thickness 0.15)
				)
				(justify left bottom)
				(hide yes)
			)
		)
		(property "Manufacturer" "Bourns"
			(at 107.95 241.3 0)
			(effects
				(font
					(size 1.27 1.27)
					(thickness 0.15)
				)
				(justify left bottom)
				(hide yes)
			)
		)
		(property "License" "Apache-2.0"
			(at 105.41 241.3 0)
			(effects
				(font
					(size 1.27 1.27)
					(thickness 0.15)
				)
				(justify left bottom)
				(hide yes)
			)
		)
		(property "Author" "Antmicro"
			(at 102.87 241.3 0)
			(effects
				(font
					(size 1.27 1.27)
					(thickness 0.15)
				)
				(justify left bottom)
				(hide yes)
			)
		)
		(property "Val" "10k"
			(at 133.35 260.35 90)
			(effects
				(font
					(size 1.27 1.27)
					(thickness 0.15)
				)
				(justify left)
			)
		)
		(property "Tolerance" "1%"
			(at 120.65 241.3 0)
			(effects
				(font
					(size 1.27 1.27)
				)
				(justify left bottom)
				(hide yes)
			)
		)
		(pin "1"
		)
		(pin "2"
		)
		(instances
			(project "jetson-agx-thor-baseboard"
				(path ""
					(reference "R126")
					(unit 1)
				)
			)
		)
	)
	(symbol
		(lib_id "antmicroB2BConnectors:Hermaphroditic_Molex_203456-0003_CUSTOM_Jetson_AGX_Thor_H8mm")
		(at 43.18 238.76 0)
		(mirror y)
		(unit 10)
		(exclude_from_sim no)
		(in_bom yes)
		(on_board yes)
		(dnp no)
		(fields_autoplaced yes)
		(property "Reference" "J1"
			(at 30.48 231.14 0)
			(effects
				(font
					(size 1.27 1.27)
				)
			)
		)
		(property "Value" "Hermaphroditic_Molex_203456-0003_CUSTOM_Jetson_AGX_Thor_H8mm"
			(at -33.274 244.856 0)
			(effects
				(font
					(size 1.27 1.27)
				)
				(justify left bottom)
				(hide yes)
			)
		)
		(property "Footprint" "antmicro-footprints:Conn_Hermaphroditic_Molex_203456-0003_mirrored"
			(at -33.274 247.142 0)
			(effects
				(font
					(size 1.27 1.27)
				)
				(justify left bottom)
				(hide yes)
			)
		)
		(property "Datasheet" "https://www.molex.com/content/dam/molex/molex-dot-com/products/automated/en-us/salesdrawingpdf/203/203456/2034560003_sd.pdf?inline"
			(at -33.274 249.428 0)
			(effects
				(font
					(size 1.27 1.27)
				)
				(justify left bottom)
				(hide yes)
			)
		)
		(property "Description" "Mirror Mezz Hermaphroditic Connector, 5.50mm Connector Height, BGA-Attach Mounting, 7 Pair, 11 Row, 699 Circuits, 0.76µm Gold Plating, without Pegs"
			(at -33.274 258.064 0)
			(effects
				(font
					(size 1.27 1.27)
				)
				(justify left bottom)
				(hide yes)
			)
		)
		(property "MPN" "203456-0003"
			(at 30.48 233.68 0)
			(effects
				(font
					(size 1.27 1.27)
				)
			)
		)
		(property "Manufacturer" "Molex"
			(at -33.274 251.714 0)
			(effects
				(font
					(size 1.27 1.27)
				)
				(justify left bottom)
				(hide yes)
			)
		)
		(property "Author" "Antmicro"
			(at -33.274 253.746 0)
			(effects
				(font
					(size 1.27 1.27)
				)
				(justify left bottom)
				(hide yes)
			)
		)
		(property "License" "Apache-2.0"
			(at -33.274 255.778 0)
			(effects
				(font
					(size 1.27 1.27)
				)
				(justify left bottom)
				(hide yes)
			)
		)
		(pin "G3"
		)
		(pin "G32"
		)
		(pin "J65"
		)
		(pin "D65"
		)
		(pin "G20"
		)
		(pin "G21"
		)
		(pin "E37"
		)
		(pin "J64"
		)
		(pin "D50"
		)
		(pin "B19"
		)
		(pin "G64"
		)
		(pin "A3"
		)
		(pin "L34"
		)
		(pin "G65"
		)
		(pin "J63"
		)
		(pin "K3"
		)
		(pin "E2"
		)
		(pin "C33"
		)
		(pin "C21"
		)
		(pin "C28"
		)
		(pin "B4"
		)
		(pin "E1"
		)
		(pin "K40"
		)
		(pin "C24"
		)
		(pin "L32"
		)
		(pin "L33"
		)
		(pin "A46"
		)
		(pin "E9"
		)
		(pin "E36"
		)
		(pin "F30"
		)
		(pin "E64"
		)
		(pin "E25"
		)
		(pin "D7"
		)
		(pin "F34"
		)
		(pin "F35"
		)
		(pin "E20"
		)
		(pin "F3"
		)
		(pin "F63"
		)
		(pin "B10"
		)
		(pin "H25"
		)
		(pin "K25"
		)
		(pin "K24"
		)
		(pin "B26"
		)
		(pin "E11"
		)
		(pin "G8"
		)
		(pin "C8"
		)
		(pin "G30"
		)
		(pin "J30"
		)
		(pin "J31"
		)
		(pin "L63"
		)
		(pin "J20"
		)
		(pin "J21"
		)
		(pin "H44"
		)
		(pin "H47"
		)
		(pin "J52"
		)
		(pin "J53"
		)
		(pin "K5"
		)
		(pin "C1"
		)
		(pin "H63"
		)
		(pin "H7"
		)
		(pin "C2"
		)
		(pin "B63"
		)
		(pin "C29"
		)
		(pin "K23"
		)
		(pin "K26"
		)
		(pin "B12"
		)
		(pin "B13"
		)
		(pin "D12"
		)
		(pin "D13"
		)
		(pin "D24"
		)
		(pin "D25"
		)
		(pin "E17"
		)
		(pin "K45"
		)
		(pin "K48"
		)
		(pin "K17"
		)
		(pin "K16"
		)
		(pin "F12"
		)
		(pin "K29"
		)
		(pin "K28"
		)
		(pin "G31"
		)
		(pin "H8"
		)
		(pin "G4"
		)
		(pin "E4"
		)
		(pin "F5"
		)
		(pin "L10"
		)
		(pin "L11"
		)
		(pin "D32"
		)
		(pin "J35"
		)
		(pin "J34"
		)
		(pin "A34"
		)
		(pin "J33"
		)
		(pin "J36"
		)
		(pin "C51"
		)
		(pin "C50"
		)
		(pin "H49"
		)
		(pin "G49"
		)
		(pin "G52"
		)
		(pin "G24"
		)
		(pin "G25"
		)
		(pin "E38"
		)
		(pin "H43"
		)
		(pin "H42"
		)
		(pin "G41"
		)
		(pin "F31"
		)
		(pin "B31"
		)
		(pin "B3"
		)
		(pin "A40"
		)
		(pin "F64"
		)
		(pin "D64"
		)
		(pin "A4"
		)
		(pin "D6"
		)
		(pin "B6"
		)
		(pin "A5"
		)
		(pin "E8"
		)
		(pin "J60"
		)
		(pin "F61"
		)
		(pin "A33"
		)
		(pin "D3"
		)
		(pin "B57"
		)
		(pin "G56"
		)
		(pin "E51"
		)
		(pin "E50"
		)
		(pin "K56"
		)
		(pin "G5"
		)
		(pin "B55"
		)
		(pin "B30"
		)
		(pin "B23"
		)
		(pin "C14"
		)
		(pin "G15"
		)
		(pin "G14"
		)
		(pin "D33"
		)
		(pin "J43"
		)
		(pin "J46"
		)
		(pin "E28"
		)
		(pin "C52"
		)
		(pin "F22"
		)
		(pin "F19"
		)
		(pin "C13"
		)
		(pin "L55"
		)
		(pin "B22"
		)
		(pin "L61"
		)
		(pin "L58"
		)
		(pin "C63"
		)
		(pin "H64"
		)
		(pin "D60"
		)
		(pin "E61"
		)
		(pin "D62"
		)
		(pin "F60"
		)
		(pin "L19"
		)
		(pin "B36"
		)
		(pin "D10"
		)
		(pin "B29"
		)
		(pin "B28"
		)
		(pin "F23"
		)
		(pin "H3"
		)
		(pin "H38"
		)
		(pin "H39"
		)
		(pin "D28"
		)
		(pin "D29"
		)
		(pin "D20"
		)
		(pin "D21"
		)
		(pin "J3"
		)
		(pin "J32"
		)
		(pin "J62"
		)
		(pin "J8"
		)
		(pin "D11"
		)
		(pin "H13"
		)
		(pin "H24"
		)
		(pin "E57"
		)
		(pin "D49"
		)
		(pin "D48"
		)
		(pin "A10"
		)
		(pin "G42"
		)
		(pin "J41"
		)
		(pin "J42"
		)
		(pin "B43"
		)
		(pin "J37"
		)
		(pin "J40"
		)
		(pin "K54"
		)
		(pin "G58"
		)
		(pin "A57"
		)
		(pin "C58"
		)
		(pin "C56"
		)
		(pin "H4"
		)
		(pin "H41"
		)
		(pin "B38"
		)
		(pin "K55"
		)
		(pin "K63"
		)
		(pin "K10"
		)
		(pin "J11"
		)
		(pin "E27"
		)
		(pin "E40"
		)
		(pin "B9"
		)
		(pin "J10"
		)
		(pin "K9"
		)
		(pin "E31"
		)
		(pin "L25"
		)
		(pin "L28"
		)
		(pin "E60"
		)
		(pin "A53"
		)
		(pin "C53"
		)
		(pin "J49"
		)
		(pin "J56"
		)
		(pin "A63"
		)
		(pin "A38"
		)
		(pin "E5"
		)
		(pin "B54"
		)
		(pin "A54"
		)
		(pin "C4"
		)
		(pin "F53"
		)
		(pin "E53"
		)
		(pin "D61"
		)
		(pin "A37"
		)
		(pin "D30"
		)
		(pin "A48"
		)
		(pin "H55"
		)
		(pin "L57"
		)
		(pin "E34"
		)
		(pin "F37"
		)
		(pin "F36"
		)
		(pin "E35"
		)
		(pin "G39"
		)
		(pin "K20"
		)
		(pin "H20"
		)
		(pin "C37"
		)
		(pin "K41"
		)
		(pin "K42"
		)
		(pin "G53"
		)
		(pin "G54"
		)
		(pin "C18"
		)
		(pin "F62"
		)
		(pin "F7"
		)
		(pin "J47"
		)
		(pin "J48"
		)
		(pin "K46"
		)
		(pin "B11"
		)
		(pin "J14"
		)
		(pin "J15"
		)
		(pin "C15"
		)
		(pin "L40"
		)
		(pin "L43"
		)
		(pin "C43"
		)
		(pin "G23"
		)
		(pin "G22"
		)
		(pin "G35"
		)
		(pin "F16"
		)
		(pin "F17"
		)
		(pin "F24"
		)
		(pin "L54"
		)
		(pin "L62"
		)
		(pin "L38"
		)
		(pin "B33"
		)
		(pin "B32"
		)
		(pin "K19"
		)
		(pin "K22"
		)
		(pin "D57"
		)
		(pin "E62"
		)
		(pin "G12"
		)
		(pin "G13"
		)
		(pin "D51"
		)
		(pin "D52"
		)
		(pin "B51"
		)
		(pin "K31"
		)
		(pin "K34"
		)
		(pin "D47"
		)
		(pin "C54"
		)
		(pin "D54"
		)
		(pin "J51"
		)
		(pin "K52"
		)
		(pin "D37"
		)
		(pin "F4"
		)
		(pin "F41"
		)
		(pin "B18"
		)
		(pin "D18"
		)
		(pin "L59"
		)
		(pin "F6"
		)
		(pin "H16"
		)
		(pin "G18"
		)
		(pin "H17"
		)
		(pin "D44"
		)
		(pin "J5"
		)
		(pin "J6"
		)
		(pin "J7"
		)
		(pin "J19"
		)
		(pin "H50"
		)
		(pin "H56"
		)
		(pin "F32"
		)
		(pin "F33"
		)
		(pin "E23"
		)
		(pin "L46"
		)
		(pin "L7"
		)
		(pin "J16"
		)
		(pin "J17"
		)
		(pin "D53"
		)
		(pin "E24"
		)
		(pin "C46"
		)
		(pin "E12"
		)
		(pin "E30"
		)
		(pin "D9"
		)
		(pin "B5"
		)
		(pin "K7"
		)
		(pin "L35"
		)
		(pin "B16"
		)
		(pin "B17"
		)
		(pin "K32"
		)
		(pin "K12"
		)
		(pin "H12"
		)
		(pin "J24"
		)
		(pin "J25"
		)
		(pin "E48"
		)
		(pin "C44"
		)
		(pin "C45"
		)
		(pin "D42"
		)
		(pin "F2"
		)
		(pin "B50"
		)
		(pin "L53"
		)
		(pin "F15"
		)
		(pin "H1"
		)
		(pin "E63"
		)
		(pin "D27"
		)
		(pin "D5"
		)
		(pin "G6"
		)
		(pin "J18"
		)
		(pin "H5"
		)
		(pin "K6"
		)
		(pin "F65"
		)
		(pin "G63"
		)
		(pin "B25"
		)
		(pin "B24"
		)
		(pin "L26"
		)
		(pin "A28"
		)
		(pin "J39"
		)
		(pin "D36"
		)
		(pin "B48"
		)
		(pin "B49"
		)
		(pin "E65"
		)
		(pin "D35"
		)
		(pin "E21"
		)
		(pin "F38"
		)
		(pin "F39"
		)
		(pin "A11"
		)
		(pin "G11"
		)
		(pin "G10"
		)
		(pin "H2"
		)
		(pin "C3"
		)
		(pin "F54"
		)
		(pin "G55"
		)
		(pin "B37"
		)
		(pin "F13"
		)
		(pin "C11"
		)
		(pin "C10"
		)
		(pin "D16"
		)
		(pin "D17"
		)
		(pin "A19"
		)
		(pin "J27"
		)
		(pin "H28"
		)
		(pin "H29"
		)
		(pin "C23"
		)
		(pin "C22"
		)
		(pin "B47"
		)
		(pin "B41"
		)
		(pin "D14"
		)
		(pin "F27"
		)
		(pin "D38"
		)
		(pin "C17"
		)
		(pin "H48"
		)
		(pin "G51"
		)
		(pin "G50"
		)
		(pin "B39"
		)
		(pin "A60"
		)
		(pin "D58"
		)
		(pin "G61"
		)
		(pin "H59"
		)
		(pin "G60"
		)
		(pin "L13"
		)
		(pin "L16"
		)
		(pin "B53"
		)
		(pin "L36"
		)
		(pin "L37"
		)
		(pin "C36"
		)
		(pin "A18"
		)
		(pin "F56"
		)
		(pin "A39"
		)
		(pin "E59"
		)
		(pin "F59"
		)
		(pin "F14"
		)
		(pin "L48"
		)
		(pin "J54"
		)
		(pin "H53"
		)
		(pin "E55"
		)
		(pin "A45"
		)
		(pin "C47"
		)
		(pin "C48"
		)
		(pin "F40"
		)
		(pin "D26"
		)
		(pin "A55"
		)
		(pin "J55"
		)
		(pin "A47"
		)
		(pin "F44"
		)
		(pin "F47"
		)
		(pin "H45"
		)
		(pin "B45"
		)
		(pin "B46"
		)
		(pin "A44"
		)
		(pin "J9"
		)
		(pin "H10"
		)
		(pin "L18"
		)
		(pin "D34"
		)
		(pin "C34"
		)
		(pin "C35"
		)
		(pin "E43"
		)
		(pin "D2"
		)
		(pin "G57"
		)
		(pin "G62"
		)
		(pin "G34"
		)
		(pin "K21"
		)
		(pin "L8"
		)
		(pin "J61"
		)
		(pin "K61"
		)
		(pin "G37"
		)
		(pin "G40"
		)
		(pin "F18"
		)
		(pin "G28"
		)
		(pin "G29"
		)
		(pin "E16"
		)
		(pin "L42"
		)
		(pin "C12"
		)
		(pin "E49"
		)
		(pin "C32"
		)
		(pin "J4"
		)
		(pin "B59"
		)
		(pin "A59"
		)
		(pin "B62"
		)
		(pin "C61"
		)
		(pin "E19"
		)
		(pin "E18"
		)
		(pin "C19"
		)
		(pin "G19"
		)
		(pin "C59"
		)
		(pin "C60"
		)
		(pin "K59"
		)
		(pin "D63"
		)
		(pin "H62"
		)
		(pin "K60"
		)
		(pin "L4"
		)
		(pin "L6"
		)
		(pin "L5"
		)
		(pin "J45"
		)
		(pin "K44"
		)
		(pin "K43"
		)
		(pin "H46"
		)
		(pin "A22"
		)
		(pin "A23"
		)
		(pin "F49"
		)
		(pin "G48"
		)
		(pin "G47"
		)
		(pin "E47"
		)
		(pin "F42"
		)
		(pin "E42"
		)
		(pin "E41"
		)
		(pin "E39"
		)
		(pin "B34"
		)
		(pin "C9"
		)
		(pin "C65"
		)
		(pin "A29"
		)
		(pin "A9"
		)
		(pin "A32"
		)
		(pin "D39"
		)
		(pin "J2"
		)
		(pin "A43"
		)
		(pin "K51"
		)
		(pin "E6"
		)
		(pin "E7"
		)
		(pin "F8"
		)
		(pin "B8"
		)
		(pin "L50"
		)
		(pin "L49"
		)
		(pin "L9"
		)
		(pin "L44"
		)
		(pin "L45"
		)
		(pin "J50"
		)
		(pin "G38"
		)
		(pin "H36"
		)
		(pin "H37"
		)
		(pin "F58"
		)
		(pin "D59"
		)
		(pin "F26"
		)
		(pin "L56"
		)
		(pin "A61"
		)
		(pin "H34"
		)
		(pin "H35"
		)
		(pin "C55"
		)
		(pin "A16"
		)
		(pin "A12"
		)
		(pin "H60"
		)
		(pin "L22"
		)
		(pin "A17"
		)
		(pin "A20"
		)
		(pin "L47"
		)
		(pin "A24"
		)
		(pin "G2"
		)
		(pin "A21"
		)
		(pin "F1"
		)
		(pin "A13"
		)
		(pin "A36"
		)
		(pin "D19"
		)
		(pin "L29"
		)
		(pin "L3"
		)
		(pin "L52"
		)
		(pin "A6"
		)
		(pin "B21"
		)
		(pin "B20"
		)
		(pin "G43"
		)
		(pin "G46"
		)
		(pin "D41"
		)
		(pin "A30"
		)
		(pin "A31"
		)
		(pin "L27"
		)
		(pin "A25"
		)
		(pin "K27"
		)
		(pin "K30"
		)
		(pin "C25"
		)
		(pin "K15"
		)
		(pin "K18"
		)
		(pin "E13"
		)
		(pin "L30"
		)
		(pin "B44"
		)
		(pin "E29"
		)
		(pin "L23"
		)
		(pin "F11"
		)
		(pin "B35"
		)
		(pin "D4"
		)
		(pin "E33"
		)
		(pin "A52"
		)
		(pin "G1"
		)
		(pin "E32"
		)
		(pin "A35"
		)
		(pin "H32"
		)
		(pin "H33"
		)
		(pin "K50"
		)
		(pin "L31"
		)
		(pin "A26"
		)
		(pin "A27"
		)
		(pin "F25"
		)
		(pin "F28"
		)
		(pin "F29"
		)
		(pin "K11"
		)
		(pin "K14"
		)
		(pin "B15"
		)
		(pin "K8"
		)
		(pin "L12"
		)
		(pin "B42"
		)
		(pin "A41"
		)
		(pin "A42"
		)
		(pin "C42"
		)
		(pin "K57"
		)
		(pin "E54"
		)
		(pin "K62"
		)
		(pin "E58"
		)
		(pin "B60"
		)
		(pin "H26"
		)
		(pin "H27"
		)
		(pin "D23"
		)
		(pin "D15"
		)
		(pin "L60"
		)
		(pin "G16"
		)
		(pin "G17"
		)
		(pin "H30"
		)
		(pin "H31"
		)
		(pin "C49"
		)
		(pin "H21"
		)
		(pin "K13"
		)
		(pin "H18"
		)
		(pin "H19"
		)
		(pin "K47"
		)
		(pin "A15"
		)
		(pin "A14"
		)
		(pin "C31"
		)
		(pin "C30"
		)
		(pin "D43"
		)
		(pin "D46"
		)
		(pin "D45"
		)
		(pin "J44"
		)
		(pin "E44"
		)
		(pin "G44"
		)
		(pin "G45"
		)
		(pin "F48"
		)
		(pin "A62"
		)
		(pin "G7"
		)
		(pin "L15"
		)
		(pin "F10"
		)
		(pin "F9"
		)
		(pin "C39"
		)
		(pin "A58"
		)
		(pin "B58"
		)
		(pin "H52"
		)
		(pin "C38"
		)
		(pin "E26"
		)
		(pin "F52"
		)
		(pin "F51"
		)
		(pin "C41"
		)
		(pin "F46"
		)
		(pin "F45"
		)
		(pin "E45"
		)
		(pin "J59"
		)
		(pin "A7"
		)
		(pin "E10"
		)
		(pin "C5"
		)
		(pin "H65"
		)
		(pin "B61"
		)
		(pin "H61"
		)
		(pin "L51"
		)
		(pin "H54"
		)
		(pin "K53"
		)
		(pin "C40"
		)
		(pin "E22"
		)
		(pin "E15"
		)
		(pin "E14"
		)
		(pin "K33"
		)
		(pin "J22"
		)
		(pin "J23"
		)
		(pin "D40"
		)
		(pin "B40"
		)
		(pin "K36"
		)
		(pin "J38"
		)
		(pin "F20"
		)
		(pin "F21"
		)
		(pin "F43"
		)
		(pin "K37"
		)
		(pin "L41"
		)
		(pin "C57"
		)
		(pin "E56"
		)
		(pin "F55"
		)
		(pin "D56"
		)
		(pin "J12"
		)
		(pin "J13"
		)
		(pin "C16"
		)
		(pin "B27"
		)
		(pin "G9"
		)
		(pin "H11"
		)
		(pin "H22"
		)
		(pin "H23"
		)
		(pin "B52"
		)
		(pin "A51"
		)
		(pin "A50"
		)
		(pin "H9"
		)
		(pin "L14"
		)
		(pin "D8"
		)
		(pin "C7"
		)
		(pin "D31"
		)
		(pin "D22"
		)
		(pin "G27"
		)
		(pin "G26"
		)
		(pin "J26"
		)
		(pin "L17"
		)
		(pin "L20"
		)
		(pin "H14"
		)
		(pin "H15"
		)
		(pin "E52"
		)
		(pin "B14"
		)
		(pin "H6"
		)
		(pin "K58"
		)
		(pin "H57"
		)
		(pin "J58"
		)
		(pin "H58"
		)
		(pin "L21"
		)
		(pin "L24"
		)
		(pin "E3"
		)
		(pin "C6"
		)
		(pin "G59"
		)
		(pin "H40"
		)
		(pin "C20"
		)
		(pin "G33"
		)
		(pin "G36"
		)
		(pin "B7"
		)
		(pin "J1"
		)
		(pin "E46"
		)
		(pin "D1"
		)
		(pin "A8"
		)
		(pin "K49"
		)
		(pin "H51"
		)
		(pin "C62"
		)
		(pin "C64"
		)
		(pin "A49"
		)
		(pin "L39"
		)
		(pin "B56"
		)
		(pin "J57"
		)
		(pin "A56"
		)
		(pin "D55"
		)
		(pin "K35"
		)
		(pin "K38"
		)
		(pin "J28"
		)
		(pin "J29"
		)
		(pin "K39"
		)
		(pin "K4"
		)
		(pin "C27"
		)
		(pin "C26"
		)
		(pin "F50"
		)
		(pin "F57"
		)
		(instances
			(project ""
				(path ""
					(reference "J1")
					(unit 10)
				)
			)
		)
	)
	(symbol
		(lib_id "antmicroCapacitors0402:C_100n_0402")
		(at 365.76 133.35 0)
		(mirror x)
		(unit 1)
		(exclude_from_sim no)
		(in_bom yes)
		(on_board yes)
		(dnp no)
		(property "Reference" "C352"
			(at 374.65 132.08 0)
			(effects
				(font
					(size 1.27 1.27)
				)
				(justify right)
			)
		)
		(property "Value" "C_100n_0402"
			(at 386.08 123.19 0)
			(effects
				(font
					(size 1.27 1.27)
					(thickness 0.15)
				)
				(justify left bottom)
				(hide yes)
			)
		)
		(property "Footprint" "antmicro-footprints:C_0402_1005Metric"
			(at 386.08 120.65 0)
			(effects
				(font
					(size 1.27 1.27)
					(thickness 0.15)
				)
				(justify left bottom)
				(hide yes)
			)
		)
		(property "Datasheet" "https://www.murata.com/products/productdetail?partno=GRM155R61H104KE14%23"
			(at 386.08 118.11 0)
			(effects
				(font
					(size 1.27 1.27)
					(thickness 0.15)
				)
				(justify left bottom)
				(hide yes)
			)
		)
		(property "Description" "SMD Multilayer Ceramic Capacitor, 0.1 µF, 50 V, 0402 [1005 Metric], ± 10%, X5R, GRM Series"
			(at 365.76 133.35 0)
			(effects
				(font
					(size 1.27 1.27)
				)
				(hide yes)
			)
		)
		(property "Manufacturer" "Murata"
			(at 386.08 113.03 0)
			(effects
				(font
					(size 1.27 1.27)
					(thickness 0.15)
				)
				(justify left bottom)
				(hide yes)
			)
		)
		(property "MPN" "GRM155R61H104KE14D"
			(at 386.08 115.57 0)
			(effects
				(font
					(size 1.27 1.27)
					(thickness 0.15)
				)
				(justify left bottom)
				(hide yes)
			)
		)
		(property "Val" "100n"
			(at 367.284 132.334 0)
			(effects
				(font
					(size 1.27 1.27)
					(thickness 0.15)
				)
				(justify right)
			)
		)
		(property "License" "Apache-2.0"
			(at 386.08 110.49 0)
			(effects
				(font
					(size 1.27 1.27)
					(thickness 0.15)
				)
				(justify left bottom)
				(hide yes)
			)
		)
		(property "Author" "Antmicro"
			(at 386.08 107.95 0)
			(effects
				(font
					(size 1.27 1.27)
					(thickness 0.15)
				)
				(justify left bottom)
				(hide yes)
			)
		)
		(property "Voltage" "50V"
			(at 386.08 105.41 0)
			(effects
				(font
					(size 1.27 1.27)
				)
				(justify left bottom)
				(hide yes)
			)
		)
		(property "Dielectric" "X5R"
			(at 386.08 102.87 0)
			(effects
				(font
					(size 1.27 1.27)
				)
				(justify left bottom)
				(hide yes)
			)
		)
		(pin "1"
		)
		(pin "2"
		)
		(instances
			(project "jetson-agx-thor-baseboard"
				(path ""
					(reference "C352")
					(unit 1)
				)
			)
		)
	)
	(symbol
		(lib_id "antmicroCapacitors0402:C_100n_0402")
		(at 287.02 100.33 0)
		(mirror x)
		(unit 1)
		(exclude_from_sim no)
		(in_bom yes)
		(on_board yes)
		(dnp no)
		(property "Reference" "C339"
			(at 295.656 99.06 0)
			(effects
				(font
					(size 1.27 1.27)
				)
				(justify right)
			)
		)
		(property "Value" "C_100n_0402"
			(at 307.34 90.17 0)
			(effects
				(font
					(size 1.27 1.27)
					(thickness 0.15)
				)
				(justify left bottom)
				(hide yes)
			)
		)
		(property "Footprint" "antmicro-footprints:C_0402_1005Metric"
			(at 307.34 87.63 0)
			(effects
				(font
					(size 1.27 1.27)
					(thickness 0.15)
				)
				(justify left bottom)
				(hide yes)
			)
		)
		(property "Datasheet" "https://www.murata.com/products/productdetail?partno=GRM155R61H104KE14%23"
			(at 307.34 85.09 0)
			(effects
				(font
					(size 1.27 1.27)
					(thickness 0.15)
				)
				(justify left bottom)
				(hide yes)
			)
		)
		(property "Description" "SMD Multilayer Ceramic Capacitor, 0.1 µF, 50 V, 0402 [1005 Metric], ± 10%, X5R, GRM Series"
			(at 287.02 100.33 0)
			(effects
				(font
					(size 1.27 1.27)
				)
				(hide yes)
			)
		)
		(property "Manufacturer" "Murata"
			(at 307.34 80.01 0)
			(effects
				(font
					(size 1.27 1.27)
					(thickness 0.15)
				)
				(justify left bottom)
				(hide yes)
			)
		)
		(property "MPN" "GRM155R61H104KE14D"
			(at 307.34 82.55 0)
			(effects
				(font
					(size 1.27 1.27)
					(thickness 0.15)
				)
				(justify left bottom)
				(hide yes)
			)
		)
		(property "Val" "100n"
			(at 288.544 99.314 0)
			(effects
				(font
					(size 1.27 1.27)
					(thickness 0.15)
				)
				(justify right)
			)
		)
		(property "License" "Apache-2.0"
			(at 307.34 77.47 0)
			(effects
				(font
					(size 1.27 1.27)
					(thickness 0.15)
				)
				(justify left bottom)
				(hide yes)
			)
		)
		(property "Author" "Antmicro"
			(at 307.34 74.93 0)
			(effects
				(font
					(size 1.27 1.27)
					(thickness 0.15)
				)
				(justify left bottom)
				(hide yes)
			)
		)
		(property "Voltage" "50V"
			(at 307.34 72.39 0)
			(effects
				(font
					(size 1.27 1.27)
				)
				(justify left bottom)
				(hide yes)
			)
		)
		(property "Dielectric" "X5R"
			(at 307.34 69.85 0)
			(effects
				(font
					(size 1.27 1.27)
				)
				(justify left bottom)
				(hide yes)
			)
		)
		(pin "1"
		)
		(pin "2"
		)
		(instances
			(project "jetson-agx-thor-baseboard"
				(path ""
					(reference "C339")
					(unit 1)
				)
			)
		)
	)
	(symbol
		(lib_id "antmicropower:GND")
		(at 274.32 273.05 0)
		(unit 1)
		(exclude_from_sim no)
		(in_bom yes)
		(on_board yes)
		(dnp no)
		(property "Reference" "#PWR0345"
			(at 283.21 275.59 0)
			(effects
				(font
					(size 1.27 1.27)
					(thickness 0.15)
				)
				(justify left bottom)
				(hide yes)
			)
		)
		(property "Value" "GND"
			(at 274.32 276.86 0)
			(effects
				(font
					(size 1.27 1.27)
					(thickness 0.15)
				)
			)
		)
		(property "Footprint" ""
			(at 283.21 280.67 0)
			(effects
				(font
					(size 1.27 1.27)
					(thickness 0.15)
				)
				(justify left bottom)
				(hide yes)
			)
		)
		(property "Datasheet" ""
			(at 283.21 285.75 0)
			(effects
				(font
					(size 1.27 1.27)
					(thickness 0.15)
				)
				(justify left bottom)
				(hide yes)
			)
		)
		(property "Description" ""
			(at 274.32 273.05 0)
			(effects
				(font
					(size 1.27 1.27)
				)
				(hide yes)
			)
		)
		(property "Author" "Antmicro"
			(at 283.21 280.67 0)
			(effects
				(font
					(size 1.27 1.27)
					(thickness 0.15)
				)
				(justify left bottom)
				(hide yes)
			)
		)
		(property "License" "Apache-2.0"
			(at 283.21 283.21 0)
			(effects
				(font
					(size 1.27 1.27)
					(thickness 0.15)
				)
				(justify left bottom)
				(hide yes)
			)
		)
		(pin "1"
		)
		(instances
			(project "jetson-agx-thor-baseboard"
				(path ""
					(reference "#PWR0345")
					(unit 1)
				)
			)
		)
	)
	(symbol
		(lib_id "antmicroCapacitors0402:C_100n_0402")
		(at 287.02 125.73 0)
		(mirror x)
		(unit 1)
		(exclude_from_sim no)
		(in_bom yes)
		(on_board yes)
		(dnp no)
		(property "Reference" "C349"
			(at 295.656 124.46 0)
			(effects
				(font
					(size 1.27 1.27)
				)
				(justify right)
			)
		)
		(property "Value" "C_100n_0402"
			(at 307.34 115.57 0)
			(effects
				(font
					(size 1.27 1.27)
					(thickness 0.15)
				)
				(justify left bottom)
				(hide yes)
			)
		)
		(property "Footprint" "antmicro-footprints:C_0402_1005Metric"
			(at 307.34 113.03 0)
			(effects
				(font
					(size 1.27 1.27)
					(thickness 0.15)
				)
				(justify left bottom)
				(hide yes)
			)
		)
		(property "Datasheet" "https://www.murata.com/products/productdetail?partno=GRM155R61H104KE14%23"
			(at 307.34 110.49 0)
			(effects
				(font
					(size 1.27 1.27)
					(thickness 0.15)
				)
				(justify left bottom)
				(hide yes)
			)
		)
		(property "Description" "SMD Multilayer Ceramic Capacitor, 0.1 µF, 50 V, 0402 [1005 Metric], ± 10%, X5R, GRM Series"
			(at 287.02 125.73 0)
			(effects
				(font
					(size 1.27 1.27)
				)
				(hide yes)
			)
		)
		(property "Manufacturer" "Murata"
			(at 307.34 105.41 0)
			(effects
				(font
					(size 1.27 1.27)
					(thickness 0.15)
				)
				(justify left bottom)
				(hide yes)
			)
		)
		(property "MPN" "GRM155R61H104KE14D"
			(at 307.34 107.95 0)
			(effects
				(font
					(size 1.27 1.27)
					(thickness 0.15)
				)
				(justify left bottom)
				(hide yes)
			)
		)
		(property "Val" "100n"
			(at 288.544 124.714 0)
			(effects
				(font
					(size 1.27 1.27)
					(thickness 0.15)
				)
				(justify right)
			)
		)
		(property "License" "Apache-2.0"
			(at 307.34 102.87 0)
			(effects
				(font
					(size 1.27 1.27)
					(thickness 0.15)
				)
				(justify left bottom)
				(hide yes)
			)
		)
		(property "Author" "Antmicro"
			(at 307.34 100.33 0)
			(effects
				(font
					(size 1.27 1.27)
					(thickness 0.15)
				)
				(justify left bottom)
				(hide yes)
			)
		)
		(property "Voltage" "50V"
			(at 307.34 97.79 0)
			(effects
				(font
					(size 1.27 1.27)
				)
				(justify left bottom)
				(hide yes)
			)
		)
		(property "Dielectric" "X5R"
			(at 307.34 95.25 0)
			(effects
				(font
					(size 1.27 1.27)
				)
				(justify left bottom)
				(hide yes)
			)
		)
		(pin "1"
		)
		(pin "2"
		)
		(instances
			(project "jetson-agx-thor-baseboard"
				(path ""
					(reference "C349")
					(unit 1)
				)
			)
		)
	)
	(symbol
		(lib_id "antmicroCapacitors0402:C_100n_0402")
		(at 279.4 52.07 0)
		(mirror x)
		(unit 1)
		(exclude_from_sim no)
		(in_bom yes)
		(on_board yes)
		(dnp no)
		(property "Reference" "C318"
			(at 288.29 50.8 0)
			(effects
				(font
					(size 1.27 1.27)
				)
				(justify right)
			)
		)
		(property "Value" "C_100n_0402"
			(at 299.72 41.91 0)
			(effects
				(font
					(size 1.27 1.27)
					(thickness 0.15)
				)
				(justify left bottom)
				(hide yes)
			)
		)
		(property "Footprint" "antmicro-footprints:C_0402_1005Metric"
			(at 299.72 39.37 0)
			(effects
				(font
					(size 1.27 1.27)
					(thickness 0.15)
				)
				(justify left bottom)
				(hide yes)
			)
		)
		(property "Datasheet" "https://www.murata.com/products/productdetail?partno=GRM155R61H104KE14%23"
			(at 299.72 36.83 0)
			(effects
				(font
					(size 1.27 1.27)
					(thickness 0.15)
				)
				(justify left bottom)
				(hide yes)
			)
		)
		(property "Description" "SMD Multilayer Ceramic Capacitor, 0.1 µF, 50 V, 0402 [1005 Metric], ± 10%, X5R, GRM Series"
			(at 279.4 52.07 0)
			(effects
				(font
					(size 1.27 1.27)
				)
				(hide yes)
			)
		)
		(property "Manufacturer" "Murata"
			(at 299.72 31.75 0)
			(effects
				(font
					(size 1.27 1.27)
					(thickness 0.15)
				)
				(justify left bottom)
				(hide yes)
			)
		)
		(property "MPN" "GRM155R61H104KE14D"
			(at 299.72 34.29 0)
			(effects
				(font
					(size 1.27 1.27)
					(thickness 0.15)
				)
				(justify left bottom)
				(hide yes)
			)
		)
		(property "Val" "100n"
			(at 280.924 51.054 0)
			(effects
				(font
					(size 1.27 1.27)
					(thickness 0.15)
				)
				(justify right)
			)
		)
		(property "License" "Apache-2.0"
			(at 299.72 29.21 0)
			(effects
				(font
					(size 1.27 1.27)
					(thickness 0.15)
				)
				(justify left bottom)
				(hide yes)
			)
		)
		(property "Author" "Antmicro"
			(at 299.72 26.67 0)
			(effects
				(font
					(size 1.27 1.27)
					(thickness 0.15)
				)
				(justify left bottom)
				(hide yes)
			)
		)
		(property "Voltage" "50V"
			(at 299.72 24.13 0)
			(effects
				(font
					(size 1.27 1.27)
				)
				(justify left bottom)
				(hide yes)
			)
		)
		(property "Dielectric" "X5R"
			(at 299.72 21.59 0)
			(effects
				(font
					(size 1.27 1.27)
				)
				(justify left bottom)
				(hide yes)
			)
		)
		(pin "1"
		)
		(pin "2"
		)
		(instances
			(project "jetson-agx-thor-baseboard"
				(path ""
					(reference "C318")
					(unit 1)
				)
			)
		)
	)
	(symbol
		(lib_id "antmicroCapacitors0402:C_100n_0402")
		(at 287.02 54.61 0)
		(mirror x)
		(unit 1)
		(exclude_from_sim no)
		(in_bom yes)
		(on_board yes)
		(dnp no)
		(property "Reference" "C319"
			(at 295.656 53.34 0)
			(effects
				(font
					(size 1.27 1.27)
				)
				(justify right)
			)
		)
		(property "Value" "C_100n_0402"
			(at 307.34 44.45 0)
			(effects
				(font
					(size 1.27 1.27)
					(thickness 0.15)
				)
				(justify left bottom)
				(hide yes)
			)
		)
		(property "Footprint" "antmicro-footprints:C_0402_1005Metric"
			(at 307.34 41.91 0)
			(effects
				(font
					(size 1.27 1.27)
					(thickness 0.15)
				)
				(justify left bottom)
				(hide yes)
			)
		)
		(property "Datasheet" "https://www.murata.com/products/productdetail?partno=GRM155R61H104KE14%23"
			(at 307.34 39.37 0)
			(effects
				(font
					(size 1.27 1.27)
					(thickness 0.15)
				)
				(justify left bottom)
				(hide yes)
			)
		)
		(property "Description" "SMD Multilayer Ceramic Capacitor, 0.1 µF, 50 V, 0402 [1005 Metric], ± 10%, X5R, GRM Series"
			(at 287.02 54.61 0)
			(effects
				(font
					(size 1.27 1.27)
				)
				(hide yes)
			)
		)
		(property "Manufacturer" "Murata"
			(at 307.34 34.29 0)
			(effects
				(font
					(size 1.27 1.27)
					(thickness 0.15)
				)
				(justify left bottom)
				(hide yes)
			)
		)
		(property "MPN" "GRM155R61H104KE14D"
			(at 307.34 36.83 0)
			(effects
				(font
					(size 1.27 1.27)
					(thickness 0.15)
				)
				(justify left bottom)
				(hide yes)
			)
		)
		(property "Val" "100n"
			(at 288.544 53.594 0)
			(effects
				(font
					(size 1.27 1.27)
					(thickness 0.15)
				)
				(justify right)
			)
		)
		(property "License" "Apache-2.0"
			(at 307.34 31.75 0)
			(effects
				(font
					(size 1.27 1.27)
					(thickness 0.15)
				)
				(justify left bottom)
				(hide yes)
			)
		)
		(property "Author" "Antmicro"
			(at 307.34 29.21 0)
			(effects
				(font
					(size 1.27 1.27)
					(thickness 0.15)
				)
				(justify left bottom)
				(hide yes)
			)
		)
		(property "Voltage" "50V"
			(at 307.34 26.67 0)
			(effects
				(font
					(size 1.27 1.27)
				)
				(justify left bottom)
				(hide yes)
			)
		)
		(property "Dielectric" "X5R"
			(at 307.34 24.13 0)
			(effects
				(font
					(size 1.27 1.27)
				)
				(justify left bottom)
				(hide yes)
			)
		)
		(pin "1"
		)
		(pin "2"
		)
		(instances
			(project "jetson-agx-thor-baseboard"
				(path ""
					(reference "C319")
					(unit 1)
				)
			)
		)
	)
	(symbol
		(lib_id "antmicroResistors0402:R_10k_0402")
		(at 116.84 261.62 270)
		(mirror x)
		(unit 1)
		(exclude_from_sim no)
		(in_bom no)
		(on_board yes)
		(dnp yes)
		(fields_autoplaced yes)
		(property "Reference" "R285"
			(at 114.3 257.81 90)
			(effects
				(font
					(size 1.27 1.27)
					(thickness 0.15)
				)
				(justify right)
			)
		)
		(property "Value" "R_10k_0402"
			(at 104.14 241.3 0)
			(effects
				(font
					(size 1.27 1.27)
					(thickness 0.15)
				)
				(justify left bottom)
				(hide yes)
			)
		)
		(property "Footprint" "antmicro-footprints:R_0402_1005Metric"
			(at 101.6 241.3 0)
			(effects
				(font
					(size 1.27 1.27)
					(thickness 0.15)
				)
				(justify left bottom)
				(hide yes)
			)
		)
		(property "Datasheet" "https://www.bourns.com/docs/product-datasheets/cr.pdf"
			(at 99.06 241.3 0)
			(effects
				(font
					(size 1.27 1.27)
					(thickness 0.15)
				)
				(justify left bottom)
				(hide yes)
			)
		)
		(property "Description" "SMD Chip Resistor, 10 kohm, ± 1%, 62.5 mW, 0402 [1005 Metric], Thick Film, General Purpose"
			(at 116.84 261.62 0)
			(effects
				(font
					(size 1.27 1.27)
				)
				(hide yes)
			)
		)
		(property "MPN" "CR0402-FX-1002GLF"
			(at 96.52 241.3 0)
			(effects
				(font
					(size 1.27 1.27)
					(thickness 0.15)
				)
				(justify left bottom)
				(hide yes)
			)
		)
		(property "Manufacturer" "Bourns"
			(at 93.98 241.3 0)
			(effects
				(font
					(size 1.27 1.27)
					(thickness 0.15)
				)
				(justify left bottom)
				(hide yes)
			)
		)
		(property "License" "Apache-2.0"
			(at 91.44 241.3 0)
			(effects
				(font
					(size 1.27 1.27)
					(thickness 0.15)
				)
				(justify left bottom)
				(hide yes)
			)
		)
		(property "Author" "Antmicro"
			(at 88.9 241.3 0)
			(effects
				(font
					(size 1.27 1.27)
					(thickness 0.15)
				)
				(justify left bottom)
				(hide yes)
			)
		)
		(property "Val" "10k"
			(at 114.3 260.35 90)
			(effects
				(font
					(size 1.27 1.27)
					(thickness 0.15)
				)
				(justify right)
			)
		)
		(property "Tolerance" "1%"
			(at 106.68 241.3 0)
			(effects
				(font
					(size 1.27 1.27)
				)
				(justify left bottom)
				(hide yes)
			)
		)
		(pin "1"
		)
		(pin "2"
		)
		(instances
			(project "jetson-agx-thor-baseboard"
				(path ""
					(reference "R285")
					(unit 1)
				)
			)
		)
	)
	(symbol
		(lib_id "antmicroCapacitors0402:C_100n_0402")
		(at 287.02 105.41 0)
		(mirror x)
		(unit 1)
		(exclude_from_sim no)
		(in_bom yes)
		(on_board yes)
		(dnp no)
		(property "Reference" "C340"
			(at 295.656 104.14 0)
			(effects
				(font
					(size 1.27 1.27)
				)
				(justify right)
			)
		)
		(property "Value" "C_100n_0402"
			(at 307.34 95.25 0)
			(effects
				(font
					(size 1.27 1.27)
					(thickness 0.15)
				)
				(justify left bottom)
				(hide yes)
			)
		)
		(property "Footprint" "antmicro-footprints:C_0402_1005Metric"
			(at 307.34 92.71 0)
			(effects
				(font
					(size 1.27 1.27)
					(thickness 0.15)
				)
				(justify left bottom)
				(hide yes)
			)
		)
		(property "Datasheet" "https://www.murata.com/products/productdetail?partno=GRM155R61H104KE14%23"
			(at 307.34 90.17 0)
			(effects
				(font
					(size 1.27 1.27)
					(thickness 0.15)
				)
				(justify left bottom)
				(hide yes)
			)
		)
		(property "Description" "SMD Multilayer Ceramic Capacitor, 0.1 µF, 50 V, 0402 [1005 Metric], ± 10%, X5R, GRM Series"
			(at 287.02 105.41 0)
			(effects
				(font
					(size 1.27 1.27)
				)
				(hide yes)
			)
		)
		(property "Manufacturer" "Murata"
			(at 307.34 85.09 0)
			(effects
				(font
					(size 1.27 1.27)
					(thickness 0.15)
				)
				(justify left bottom)
				(hide yes)
			)
		)
		(property "MPN" "GRM155R61H104KE14D"
			(at 307.34 87.63 0)
			(effects
				(font
					(size 1.27 1.27)
					(thickness 0.15)
				)
				(justify left bottom)
				(hide yes)
			)
		)
		(property "Val" "100n"
			(at 288.544 104.394 0)
			(effects
				(font
					(size 1.27 1.27)
					(thickness 0.15)
				)
				(justify right)
			)
		)
		(property "License" "Apache-2.0"
			(at 307.34 82.55 0)
			(effects
				(font
					(size 1.27 1.27)
					(thickness 0.15)
				)
				(justify left bottom)
				(hide yes)
			)
		)
		(property "Author" "Antmicro"
			(at 307.34 80.01 0)
			(effects
				(font
					(size 1.27 1.27)
					(thickness 0.15)
				)
				(justify left bottom)
				(hide yes)
			)
		)
		(property "Voltage" "50V"
			(at 307.34 77.47 0)
			(effects
				(font
					(size 1.27 1.27)
				)
				(justify left bottom)
				(hide yes)
			)
		)
		(property "Dielectric" "X5R"
			(at 307.34 74.93 0)
			(effects
				(font
					(size 1.27 1.27)
				)
				(justify left bottom)
				(hide yes)
			)
		)
		(pin "1"
		)
		(pin "2"
		)
		(instances
			(project "jetson-agx-thor-baseboard"
				(path ""
					(reference "C340")
					(unit 1)
				)
			)
		)
	)
	(symbol
		(lib_id "antmicroCapacitors0402:C_100n_0402")
		(at 279.4 128.27 0)
		(mirror x)
		(unit 1)
		(exclude_from_sim no)
		(in_bom yes)
		(on_board yes)
		(dnp no)
		(property "Reference" "C346"
			(at 288.29 127 0)
			(effects
				(font
					(size 1.27 1.27)
				)
				(justify right)
			)
		)
		(property "Value" "C_100n_0402"
			(at 299.72 118.11 0)
			(effects
				(font
					(size 1.27 1.27)
					(thickness 0.15)
				)
				(justify left bottom)
				(hide yes)
			)
		)
		(property "Footprint" "antmicro-footprints:C_0402_1005Metric"
			(at 299.72 115.57 0)
			(effects
				(font
					(size 1.27 1.27)
					(thickness 0.15)
				)
				(justify left bottom)
				(hide yes)
			)
		)
		(property "Datasheet" "https://www.murata.com/products/productdetail?partno=GRM155R61H104KE14%23"
			(at 299.72 113.03 0)
			(effects
				(font
					(size 1.27 1.27)
					(thickness 0.15)
				)
				(justify left bottom)
				(hide yes)
			)
		)
		(property "Description" "SMD Multilayer Ceramic Capacitor, 0.1 µF, 50 V, 0402 [1005 Metric], ± 10%, X5R, GRM Series"
			(at 279.4 128.27 0)
			(effects
				(font
					(size 1.27 1.27)
				)
				(hide yes)
			)
		)
		(property "Manufacturer" "Murata"
			(at 299.72 107.95 0)
			(effects
				(font
					(size 1.27 1.27)
					(thickness 0.15)
				)
				(justify left bottom)
				(hide yes)
			)
		)
		(property "MPN" "GRM155R61H104KE14D"
			(at 299.72 110.49 0)
			(effects
				(font
					(size 1.27 1.27)
					(thickness 0.15)
				)
				(justify left bottom)
				(hide yes)
			)
		)
		(property "Val" "100n"
			(at 280.924 127.254 0)
			(effects
				(font
					(size 1.27 1.27)
					(thickness 0.15)
				)
				(justify right)
			)
		)
		(property "License" "Apache-2.0"
			(at 299.72 105.41 0)
			(effects
				(font
					(size 1.27 1.27)
					(thickness 0.15)
				)
				(justify left bottom)
				(hide yes)
			)
		)
		(property "Author" "Antmicro"
			(at 299.72 102.87 0)
			(effects
				(font
					(size 1.27 1.27)
					(thickness 0.15)
				)
				(justify left bottom)
				(hide yes)
			)
		)
		(property "Voltage" "50V"
			(at 299.72 100.33 0)
			(effects
				(font
					(size 1.27 1.27)
				)
				(justify left bottom)
				(hide yes)
			)
		)
		(property "Dielectric" "X5R"
			(at 299.72 97.79 0)
			(effects
				(font
					(size 1.27 1.27)
				)
				(justify left bottom)
				(hide yes)
			)
		)
		(pin "1"
		)
		(pin "2"
		)
		(instances
			(project "jetson-agx-thor-baseboard"
				(path ""
					(reference "C346")
					(unit 1)
				)
			)
		)
	)
	(symbol
		(lib_id "antmicroB2BConnectors:Hermaphroditic_Molex_203456-0003_CUSTOM_Jetson_AGX_Thor_H8mm")
		(at 81.28 105.41 0)
		(unit 2)
		(exclude_from_sim no)
		(in_bom yes)
		(on_board yes)
		(dnp no)
		(fields_autoplaced yes)
		(property "Reference" "J1"
			(at 102.87 96.52 0)
			(effects
				(font
					(size 1.27 1.27)
				)
			)
		)
		(property "Value" "Hermaphroditic_Molex_203456-0003_CUSTOM_Jetson_AGX_Thor_H8mm"
			(at 157.734 111.506 0)
			(effects
				(font
					(size 1.27 1.27)
				)
				(justify left bottom)
				(hide yes)
			)
		)
		(property "Footprint" "antmicro-footprints:Conn_Hermaphroditic_Molex_203456-0003_mirrored"
			(at 157.734 113.792 0)
			(effects
				(font
					(size 1.27 1.27)
				)
				(justify left bottom)
				(hide yes)
			)
		)
		(property "Datasheet" "https://www.molex.com/content/dam/molex/molex-dot-com/products/automated/en-us/salesdrawingpdf/203/203456/2034560003_sd.pdf?inline"
			(at 157.734 116.078 0)
			(effects
				(font
					(size 1.27 1.27)
				)
				(justify left bottom)
				(hide yes)
			)
		)
		(property "Description" "Mirror Mezz Hermaphroditic Connector, 5.50mm Connector Height, BGA-Attach Mounting, 7 Pair, 11 Row, 699 Circuits, 0.76µm Gold Plating, without Pegs"
			(at 157.734 124.714 0)
			(effects
				(font
					(size 1.27 1.27)
				)
				(justify left bottom)
				(hide yes)
			)
		)
		(property "MPN" "203456-0003"
			(at 102.87 99.06 0)
			(effects
				(font
					(size 1.27 1.27)
				)
			)
		)
		(property "Manufacturer" "Molex"
			(at 157.734 118.364 0)
			(effects
				(font
					(size 1.27 1.27)
				)
				(justify left bottom)
				(hide yes)
			)
		)
		(property "Author" "Antmicro"
			(at 157.734 120.396 0)
			(effects
				(font
					(size 1.27 1.27)
				)
				(justify left bottom)
				(hide yes)
			)
		)
		(property "License" "Apache-2.0"
			(at 157.734 122.428 0)
			(effects
				(font
					(size 1.27 1.27)
				)
				(justify left bottom)
				(hide yes)
			)
		)
		(pin "J37"
		)
		(pin "D37"
		)
		(pin "C40"
		)
		(pin "J40"
		)
		(pin "C30"
		)
		(pin "D28"
		)
		(pin "F57"
		)
		(pin "F45"
		)
		(pin "B48"
		)
		(pin "F46"
		)
		(pin "C41"
		)
		(pin "D23"
		)
		(pin "G48"
		)
		(pin "C42"
		)
		(pin "J5"
		)
		(pin "E56"
		)
		(pin "D27"
		)
		(pin "C27"
		)
		(pin "E28"
		)
		(pin "D63"
		)
		(pin "A40"
		)
		(pin "J21"
		)
		(pin "L24"
		)
		(pin "L59"
		)
		(pin "B27"
		)
		(pin "D1"
		)
		(pin "C16"
		)
		(pin "H12"
		)
		(pin "H19"
		)
		(pin "F9"
		)
		(pin "A42"
		)
		(pin "A41"
		)
		(pin "B42"
		)
		(pin "E7"
		)
		(pin "B43"
		)
		(pin "L54"
		)
		(pin "A57"
		)
		(pin "J42"
		)
		(pin "B12"
		)
		(pin "F63"
		)
		(pin "J38"
		)
		(pin "J41"
		)
		(pin "L43"
		)
		(pin "D59"
		)
		(pin "J65"
		)
		(pin "H26"
		)
		(pin "G19"
		)
		(pin "G7"
		)
		(pin "D12"
		)
		(pin "F34"
		)
		(pin "G42"
		)
		(pin "G41"
		)
		(pin "H42"
		)
		(pin "E30"
		)
		(pin "L62"
		)
		(pin "L49"
		)
		(pin "H43"
		)
		(pin "F27"
		)
		(pin "G64"
		)
		(pin "J54"
		)
		(pin "F39"
		)
		(pin "E38"
		)
		(pin "D8"
		)
		(pin "H30"
		)
		(pin "B33"
		)
		(pin "G12"
		)
		(pin "E39"
		)
		(pin "E5"
		)
		(pin "E41"
		)
		(pin "E42"
		)
		(pin "H16"
		)
		(pin "F42"
		)
		(pin "F43"
		)
		(pin "L56"
		)
		(pin "F21"
		)
		(pin "B21"
		)
		(pin "F20"
		)
		(pin "C19"
		)
		(pin "L15"
		)
		(pin "F50"
		)
		(pin "F37"
		)
		(pin "J60"
		)
		(pin "E18"
		)
		(pin "E64"
		)
		(pin "E19"
		)
		(pin "B13"
		)
		(pin "D9"
		)
		(pin "K56"
		)
		(pin "D5"
		)
		(pin "A19"
		)
		(pin "D45"
		)
		(pin "L12"
		)
		(pin "C47"
		)
		(pin "E13"
		)
		(pin "E46"
		)
		(pin "C24"
		)
		(pin "H64"
		)
		(pin "A24"
		)
		(pin "F3"
		)
		(pin "L27"
		)
		(pin "H40"
		)
		(pin "C20"
		)
		(pin "G13"
		)
		(pin "K29"
		)
		(pin "H65"
		)
		(pin "A9"
		)
		(pin "A13"
		)
		(pin "A30"
		)
		(pin "B34"
		)
		(pin "E12"
		)
		(pin "C11"
		)
		(pin "E23"
		)
		(pin "D7"
		)
		(pin "D18"
		)
		(pin "F65"
		)
		(pin "D53"
		)
		(pin "H35"
		)
		(pin "A25"
		)
		(pin "C3"
		)
		(pin "J33"
		)
		(pin "H39"
		)
		(pin "B50"
		)
		(pin "A63"
		)
		(pin "G65"
		)
		(pin "B22"
		)
		(pin "B18"
		)
		(pin "E57"
		)
		(pin "D29"
		)
		(pin "D19"
		)
		(pin "F25"
		)
		(pin "F28"
		)
		(pin "L10"
		)
		(pin "C31"
		)
		(pin "G1"
		)
		(pin "E16"
		)
		(pin "E40"
		)
		(pin "E20"
		)
		(pin "D50"
		)
		(pin "D57"
		)
		(pin "F59"
		)
		(pin "J64"
		)
		(pin "D49"
		)
		(pin "E62"
		)
		(pin "E24"
		)
		(pin "J26"
		)
		(pin "K25"
		)
		(pin "G26"
		)
		(pin "H29"
		)
		(pin "B29"
		)
		(pin "B38"
		)
		(pin "C10"
		)
		(pin "F12"
		)
		(pin "A46"
		)
		(pin "K12"
		)
		(pin "E17"
		)
		(pin "F16"
		)
		(pin "H25"
		)
		(pin "K16"
		)
		(pin "J30"
		)
		(pin "D17"
		)
		(pin "K37"
		)
		(pin "B5"
		)
		(pin "E50"
		)
		(pin "D16"
		)
		(pin "D4"
		)
		(pin "G40"
		)
		(pin "H7"
		)
		(pin "A45"
		)
		(pin "H45"
		)
		(pin "C18"
		)
		(pin "G36"
		)
		(pin "B58"
		)
		(pin "A10"
		)
		(pin "L52"
		)
		(pin "G54"
		)
		(pin "G53"
		)
		(pin "D20"
		)
		(pin "K50"
		)
		(pin "H61"
		)
		(pin "C54"
		)
		(pin "H33"
		)
		(pin "H51"
		)
		(pin "H62"
		)
		(pin "F44"
		)
		(pin "H32"
		)
		(pin "C6"
		)
		(pin "L25"
		)
		(pin "A35"
		)
		(pin "D55"
		)
		(pin "L9"
		)
		(pin "F41"
		)
		(pin "A56"
		)
		(pin "J18"
		)
		(pin "K7"
		)
		(pin "D13"
		)
		(pin "A34"
		)
		(pin "G33"
		)
		(pin "A38"
		)
		(pin "D24"
		)
		(pin "H63"
		)
		(pin "C58"
		)
		(pin "J35"
		)
		(pin "J51"
		)
		(pin "E61"
		)
		(pin "E25"
		)
		(pin "E29"
		)
		(pin "E63"
		)
		(pin "L60"
		)
		(pin "D62"
		)
		(pin "G58"
		)
		(pin "J12"
		)
		(pin "J59"
		)
		(pin "H15"
		)
		(pin "K36"
		)
		(pin "J24"
		)
		(pin "A54"
		)
		(pin "D32"
		)
		(pin "F62"
		)
		(pin "B54"
		)
		(pin "D33"
		)
		(pin "G14"
		)
		(pin "A22"
		)
		(pin "C14"
		)
		(pin "L3"
		)
		(pin "E2"
		)
		(pin "B11"
		)
		(pin "C23"
		)
		(pin "A12"
		)
		(pin "G15"
		)
		(pin "C15"
		)
		(pin "A59"
		)
		(pin "J15"
		)
		(pin "J57"
		)
		(pin "C7"
		)
		(pin "J14"
		)
		(pin "G59"
		)
		(pin "G39"
		)
		(pin "E54"
		)
		(pin "A37"
		)
		(pin "L41"
		)
		(pin "A14"
		)
		(pin "A15"
		)
		(pin "L51"
		)
		(pin "K47"
		)
		(pin "L46"
		)
		(pin "G4"
		)
		(pin "B15"
		)
		(pin "C34"
		)
		(pin "K46"
		)
		(pin "H37"
		)
		(pin "J48"
		)
		(pin "J47"
		)
		(pin "B9"
		)
		(pin "F49"
		)
		(pin "C22"
		)
		(pin "J39"
		)
		(pin "J13"
		)
		(pin "G50"
		)
		(pin "L6"
		)
		(pin "G51"
		)
		(pin "L8"
		)
		(pin "H9"
		)
		(pin "B56"
		)
		(pin "L53"
		)
		(pin "C12"
		)
		(pin "E59"
		)
		(pin "K24"
		)
		(pin "E52"
		)
		(pin "A27"
		)
		(pin "A31"
		)
		(pin "E21"
		)
		(pin "K17"
		)
		(pin "H49"
		)
		(pin "E22"
		)
		(pin "H21"
		)
		(pin "J63"
		)
		(pin "K28"
		)
		(pin "B28"
		)
		(pin "E65"
		)
		(pin "G52"
		)
		(pin "D44"
		)
		(pin "D47"
		)
		(pin "B4"
		)
		(pin "F2"
		)
		(pin "L35"
		)
		(pin "C52"
		)
		(pin "L42"
		)
		(pin "E32"
		)
		(pin "E37"
		)
		(pin "E33"
		)
		(pin "E43"
		)
		(pin "E15"
		)
		(pin "G30"
		)
		(pin "D41"
		)
		(pin "J31"
		)
		(pin "E9"
		)
		(pin "F14"
		)
		(pin "L5"
		)
		(pin "E3"
		)
		(pin "L34"
		)
		(pin "C25"
		)
		(pin "J4"
		)
		(pin "K42"
		)
		(pin "G63"
		)
		(pin "A16"
		)
		(pin "L30"
		)
		(pin "E1"
		)
		(pin "A36"
		)
		(pin "L20"
		)
		(pin "J2"
		)
		(pin "K45"
		)
		(pin "A3"
		)
		(pin "L23"
		)
		(pin "A33"
		)
		(pin "A17"
		)
		(pin "H41"
		)
		(pin "C46"
		)
		(pin "L31"
		)
		(pin "H44"
		)
		(pin "F64"
		)
		(pin "A28"
		)
		(pin "C21"
		)
		(pin "F1"
		)
		(pin "A20"
		)
		(pin "B53"
		)
		(pin "A29"
		)
		(pin "E49"
		)
		(pin "G27"
		)
		(pin "E14"
		)
		(pin "H4"
		)
		(pin "H13"
		)
		(pin "F32"
		)
		(pin "F13"
		)
		(pin "E36"
		)
		(pin "D39"
		)
		(pin "H48"
		)
		(pin "K43"
		)
		(pin "F40"
		)
		(pin "G57"
		)
		(pin "C4"
		)
		(pin "K53"
		)
		(pin "D40"
		)
		(pin "H46"
		)
		(pin "H10"
		)
		(pin "C56"
		)
		(pin "L21"
		)
		(pin "G6"
		)
		(pin "H28"
		)
		(pin "K13"
		)
		(pin "L47"
		)
		(pin "C48"
		)
		(pin "D10"
		)
		(pin "D43"
		)
		(pin "A44"
		)
		(pin "D46"
		)
		(pin "C45"
		)
		(pin "J9"
		)
		(pin "C50"
		)
		(pin "L16"
		)
		(pin "B46"
		)
		(pin "E47"
		)
		(pin "H36"
		)
		(pin "B45"
		)
		(pin "C44"
		)
		(pin "L18"
		)
		(pin "D42"
		)
		(pin "A8"
		)
		(pin "C38"
		)
		(pin "E48"
		)
		(pin "K49"
		)
		(pin "L50"
		)
		(pin "K54"
		)
		(pin "J29"
		)
		(pin "K48"
		)
		(pin "C61"
		)
		(pin "D21"
		)
		(pin "K5"
		)
		(pin "C51"
		)
		(pin "H53"
		)
		(pin "J7"
		)
		(pin "A50"
		)
		(pin "H56"
		)
		(pin "A51"
		)
		(pin "H47"
		)
		(pin "H18"
		)
		(pin "G47"
		)
		(pin "D6"
		)
		(pin "B51"
		)
		(pin "G5"
		)
		(pin "B52"
		)
		(pin "H22"
		)
		(pin "L14"
		)
		(pin "D52"
		)
		(pin "E31"
		)
		(pin "J53"
		)
		(pin "B61"
		)
		(pin "G20"
		)
		(pin "B60"
		)
		(pin "L29"
		)
		(pin "F31"
		)
		(pin "G60"
		)
		(pin "F60"
		)
		(pin "D51"
		)
		(pin "F56"
		)
		(pin "G38"
		)
		(pin "J50"
		)
		(pin "L45"
		)
		(pin "J43"
		)
		(pin "F8"
		)
		(pin "J34"
		)
		(pin "E51"
		)
		(pin "A43"
		)
		(pin "F36"
		)
		(pin "B30"
		)
		(pin "B32"
		)
		(pin "L44"
		)
		(pin "K62"
		)
		(pin "D2"
		)
		(pin "L57"
		)
		(pin "E45"
		)
		(pin "H55"
		)
		(pin "A47"
		)
		(pin "H1"
		)
		(pin "C29"
		)
		(pin "B6"
		)
		(pin "B20"
		)
		(pin "C33"
		)
		(pin "J55"
		)
		(pin "C64"
		)
		(pin "F47"
		)
		(pin "A55"
		)
		(pin "D60"
		)
		(pin "J52"
		)
		(pin "F51"
		)
		(pin "H5"
		)
		(pin "C28"
		)
		(pin "F7"
		)
		(pin "A48"
		)
		(pin "H59"
		)
		(pin "K6"
		)
		(pin "D36"
		)
		(pin "F6"
		)
		(pin "F52"
		)
		(pin "J49"
		)
		(pin "J19"
		)
		(pin "C5"
		)
		(pin "G56"
		)
		(pin "H17"
		)
		(pin "E58"
		)
		(pin "E27"
		)
		(pin "F38"
		)
		(pin "H6"
		)
		(pin "G21"
		)
		(pin "D26"
		)
		(pin "J11"
		)
		(pin "B16"
		)
		(pin "B59"
		)
		(pin "A5"
		)
		(pin "K58"
		)
		(pin "L48"
		)
		(pin "A58"
		)
		(pin "F61"
		)
		(pin "K15"
		)
		(pin "G23"
		)
		(pin "E4"
		)
		(pin "H31"
		)
		(pin "K10"
		)
		(pin "D65"
		)
		(pin "G34"
		)
		(pin "L38"
		)
		(pin "K33"
		)
		(pin "C43"
		)
		(pin "F18"
		)
		(pin "E35"
		)
		(pin "D48"
		)
		(pin "G18"
		)
		(pin "K9"
		)
		(pin "C53"
		)
		(pin "E6"
		)
		(pin "C55"
		)
		(pin "J8"
		)
		(pin "D35"
		)
		(pin "F48"
		)
		(pin "E44"
		)
		(pin "B55"
		)
		(pin "E34"
		)
		(pin "G11"
		)
		(pin "G61"
		)
		(pin "K51"
		)
		(pin "K20"
		)
		(pin "A49"
		)
		(pin "H23"
		)
		(pin "C62"
		)
		(pin "B24"
		)
		(pin "G2"
		)
		(pin "B14"
		)
		(pin "G22"
		)
		(pin "A60"
		)
		(pin "K27"
		)
		(pin "H54"
		)
		(pin "B7"
		)
		(pin "A61"
		)
		(pin "D56"
		)
		(pin "G32"
		)
		(pin "B26"
		)
		(pin "B44"
		)
		(pin "H38"
		)
		(pin "C49"
		)
		(pin "D15"
		)
		(pin "B49"
		)
		(pin "B17"
		)
		(pin "F35"
		)
		(pin "B39"
		)
		(pin "F5"
		)
		(pin "J3"
		)
		(pin "J46"
		)
		(pin "J28"
		)
		(pin "J36"
		)
		(pin "J25"
		)
		(pin "J32"
		)
		(pin "L22"
		)
		(pin "K22"
		)
		(pin "J20"
		)
		(pin "C32"
		)
		(pin "F10"
		)
		(pin "G16"
		)
		(pin "F55"
		)
		(pin "K40"
		)
		(pin "H20"
		)
		(pin "K32"
		)
		(pin "G3"
		)
		(pin "A32"
		)
		(pin "J10"
		)
		(pin "C13"
		)
		(pin "L55"
		)
		(pin "G46"
		)
		(pin "G35"
		)
		(pin "L26"
		)
		(pin "E60"
		)
		(pin "J23"
		)
		(pin "J22"
		)
		(pin "A21"
		)
		(pin "L39"
		)
		(pin "C36"
		)
		(pin "L36"
		)
		(pin "G17"
		)
		(pin "J58"
		)
		(pin "K52"
		)
		(pin "B25"
		)
		(pin "E11"
		)
		(pin "B36"
		)
		(pin "A52"
		)
		(pin "B35"
		)
		(pin "D3"
		)
		(pin "K21"
		)
		(pin "E26"
		)
		(pin "F23"
		)
		(pin "F26"
		)
		(pin "G9"
		)
		(pin "D61"
		)
		(pin "C37"
		)
		(pin "K23"
		)
		(pin "G28"
		)
		(pin "H34"
		)
		(pin "D30"
		)
		(pin "H50"
		)
		(pin "G49"
		)
		(pin "B47"
		)
		(pin "B31"
		)
		(pin "A18"
		)
		(pin "J17"
		)
		(pin "C8"
		)
		(pin "C26"
		)
		(pin "G29"
		)
		(pin "E53"
		)
		(pin "G8"
		)
		(pin "K34"
		)
		(pin "K31"
		)
		(pin "G31"
		)
		(pin "K59"
		)
		(pin "L61"
		)
		(pin "C9"
		)
		(pin "D14"
		)
		(pin "K39"
		)
		(pin "C60"
		)
		(pin "F17"
		)
		(pin "B10"
		)
		(pin "L33"
		)
		(pin "H11"
		)
		(pin "L13"
		)
		(pin "D31"
		)
		(pin "F33"
		)
		(pin "A39"
		)
		(pin "A6"
		)
		(pin "C57"
		)
		(pin "H8"
		)
		(pin "G24"
		)
		(pin "B19"
		)
		(pin "F53"
		)
		(pin "K38"
		)
		(pin "A23"
		)
		(pin "C59"
		)
		(pin "J56"
		)
		(pin "D54"
		)
		(pin "F4"
		)
		(pin "A4"
		)
		(pin "F15"
		)
		(pin "G55"
		)
		(pin "E55"
		)
		(pin "J45"
		)
		(pin "D58"
		)
		(pin "J44"
		)
		(pin "K41"
		)
		(pin "A11"
		)
		(pin "G62"
		)
		(pin "J6"
		)
		(pin "H2"
		)
		(pin "L7"
		)
		(pin "C35"
		)
		(pin "L4"
		)
		(pin "E10"
		)
		(pin "A7"
		)
		(pin "L28"
		)
		(pin "K3"
		)
		(pin "J1"
		)
		(pin "K61"
		)
		(pin "G37"
		)
		(pin "L58"
		)
		(pin "A53"
		)
		(pin "L40"
		)
		(pin "F22"
		)
		(pin "K18"
		)
		(pin "D38"
		)
		(pin "K11"
		)
		(pin "H58"
		)
		(pin "A62"
		)
		(pin "K35"
		)
		(pin "D64"
		)
		(pin "G44"
		)
		(pin "H52"
		)
		(pin "H14"
		)
		(pin "K44"
		)
		(pin "F30"
		)
		(pin "D11"
		)
		(pin "C39"
		)
		(pin "K8"
		)
		(pin "F29"
		)
		(pin "F58"
		)
		(pin "B8"
		)
		(pin "B57"
		)
		(pin "B23"
		)
		(pin "G10"
		)
		(pin "K55"
		)
		(pin "G25"
		)
		(pin "L37"
		)
		(pin "H27"
		)
		(pin "H3"
		)
		(pin "F54"
		)
		(pin "K19"
		)
		(pin "G45"
		)
		(pin "L11"
		)
		(pin "J16"
		)
		(pin "K60"
		)
		(pin "B40"
		)
		(pin "J62"
		)
		(pin "K63"
		)
		(pin "H57"
		)
		(pin "L19"
		)
		(pin "L17"
		)
		(pin "C63"
		)
		(pin "E8"
		)
		(pin "D25"
		)
		(pin "C1"
		)
		(pin "C2"
		)
		(pin "B3"
		)
		(pin "B63"
		)
		(pin "C65"
		)
		(pin "K26"
		)
		(pin "A26"
		)
		(pin "G43"
		)
		(pin "H60"
		)
		(pin "F24"
		)
		(pin "H24"
		)
		(pin "J27"
		)
		(pin "C17"
		)
		(pin "F11"
		)
		(pin "F19"
		)
		(pin "J61"
		)
		(pin "K14"
		)
		(pin "K57"
		)
		(pin "L32"
		)
		(pin "B62"
		)
		(pin "D22"
		)
		(pin "D34"
		)
		(pin "L63"
		)
		(pin "B41"
		)
		(pin "K30"
		)
		(pin "B37"
		)
		(pin "K4"
		)
		(instances
			(project ""
				(path ""
					(reference "J1")
					(unit 2)
				)
			)
		)
	)
	(symbol
		(lib_id "antmicroCapacitors0402:C_100n_0402")
		(at 373.38 85.09 0)
		(mirror x)
		(unit 1)
		(exclude_from_sim no)
		(in_bom yes)
		(on_board yes)
		(dnp no)
		(property "Reference" "C333"
			(at 382.016 83.82 0)
			(effects
				(font
					(size 1.27 1.27)
				)
				(justify right)
			)
		)
		(property "Value" "C_100n_0402"
			(at 393.7 74.93 0)
			(effects
				(font
					(size 1.27 1.27)
					(thickness 0.15)
				)
				(justify left bottom)
				(hide yes)
			)
		)
		(property "Footprint" "antmicro-footprints:C_0402_1005Metric"
			(at 393.7 72.39 0)
			(effects
				(font
					(size 1.27 1.27)
					(thickness 0.15)
				)
				(justify left bottom)
				(hide yes)
			)
		)
		(property "Datasheet" "https://www.murata.com/products/productdetail?partno=GRM155R61H104KE14%23"
			(at 393.7 69.85 0)
			(effects
				(font
					(size 1.27 1.27)
					(thickness 0.15)
				)
				(justify left bottom)
				(hide yes)
			)
		)
		(property "Description" "SMD Multilayer Ceramic Capacitor, 0.1 µF, 50 V, 0402 [1005 Metric], ± 10%, X5R, GRM Series"
			(at 373.38 85.09 0)
			(effects
				(font
					(size 1.27 1.27)
				)
				(hide yes)
			)
		)
		(property "Manufacturer" "Murata"
			(at 393.7 64.77 0)
			(effects
				(font
					(size 1.27 1.27)
					(thickness 0.15)
				)
				(justify left bottom)
				(hide yes)
			)
		)
		(property "MPN" "GRM155R61H104KE14D"
			(at 393.7 67.31 0)
			(effects
				(font
					(size 1.27 1.27)
					(thickness 0.15)
				)
				(justify left bottom)
				(hide yes)
			)
		)
		(property "Val" "100n"
			(at 374.904 84.074 0)
			(effects
				(font
					(size 1.27 1.27)
					(thickness 0.15)
				)
				(justify right)
			)
		)
		(property "License" "Apache-2.0"
			(at 393.7 62.23 0)
			(effects
				(font
					(size 1.27 1.27)
					(thickness 0.15)
				)
				(justify left bottom)
				(hide yes)
			)
		)
		(property "Author" "Antmicro"
			(at 393.7 59.69 0)
			(effects
				(font
					(size 1.27 1.27)
					(thickness 0.15)
				)
				(justify left bottom)
				(hide yes)
			)
		)
		(property "Voltage" "50V"
			(at 393.7 57.15 0)
			(effects
				(font
					(size 1.27 1.27)
				)
				(justify left bottom)
				(hide yes)
			)
		)
		(property "Dielectric" "X5R"
			(at 393.7 54.61 0)
			(effects
				(font
					(size 1.27 1.27)
				)
				(justify left bottom)
				(hide yes)
			)
		)
		(pin "1"
		)
		(pin "2"
		)
		(instances
			(project "jetson-agx-thor-baseboard"
				(path ""
					(reference "C333")
					(unit 1)
				)
			)
		)
	)
	(symbol
		(lib_id "antmicroCapacitors0402:C_100n_0402")
		(at 287.02 74.93 0)
		(mirror x)
		(unit 1)
		(exclude_from_sim no)
		(in_bom yes)
		(on_board yes)
		(dnp no)
		(property "Reference" "C329"
			(at 295.656 73.66 0)
			(effects
				(font
					(size 1.27 1.27)
				)
				(justify right)
			)
		)
		(property "Value" "C_100n_0402"
			(at 307.34 64.77 0)
			(effects
				(font
					(size 1.27 1.27)
					(thickness 0.15)
				)
				(justify left bottom)
				(hide yes)
			)
		)
		(property "Footprint" "antmicro-footprints:C_0402_1005Metric"
			(at 307.34 62.23 0)
			(effects
				(font
					(size 1.27 1.27)
					(thickness 0.15)
				)
				(justify left bottom)
				(hide yes)
			)
		)
		(property "Datasheet" "https://www.murata.com/products/productdetail?partno=GRM155R61H104KE14%23"
			(at 307.34 59.69 0)
			(effects
				(font
					(size 1.27 1.27)
					(thickness 0.15)
				)
				(justify left bottom)
				(hide yes)
			)
		)
		(property "Description" "SMD Multilayer Ceramic Capacitor, 0.1 µF, 50 V, 0402 [1005 Metric], ± 10%, X5R, GRM Series"
			(at 287.02 74.93 0)
			(effects
				(font
					(size 1.27 1.27)
				)
				(hide yes)
			)
		)
		(property "Manufacturer" "Murata"
			(at 307.34 54.61 0)
			(effects
				(font
					(size 1.27 1.27)
					(thickness 0.15)
				)
				(justify left bottom)
				(hide yes)
			)
		)
		(property "MPN" "GRM155R61H104KE14D"
			(at 307.34 57.15 0)
			(effects
				(font
					(size 1.27 1.27)
					(thickness 0.15)
				)
				(justify left bottom)
				(hide yes)
			)
		)
		(property "Val" "100n"
			(at 288.544 73.914 0)
			(effects
				(font
					(size 1.27 1.27)
					(thickness 0.15)
				)
				(justify right)
			)
		)
		(property "License" "Apache-2.0"
			(at 307.34 52.07 0)
			(effects
				(font
					(size 1.27 1.27)
					(thickness 0.15)
				)
				(justify left bottom)
				(hide yes)
			)
		)
		(property "Author" "Antmicro"
			(at 307.34 49.53 0)
			(effects
				(font
					(size 1.27 1.27)
					(thickness 0.15)
				)
				(justify left bottom)
				(hide yes)
			)
		)
		(property "Voltage" "50V"
			(at 307.34 46.99 0)
			(effects
				(font
					(size 1.27 1.27)
				)
				(justify left bottom)
				(hide yes)
			)
		)
		(property "Dielectric" "X5R"
			(at 307.34 44.45 0)
			(effects
				(font
					(size 1.27 1.27)
				)
				(justify left bottom)
				(hide yes)
			)
		)
		(pin "1"
		)
		(pin "2"
		)
		(instances
			(project "jetson-agx-thor-baseboard"
				(path ""
					(reference "C329")
					(unit 1)
				)
			)
		)
	)
	(symbol
		(lib_id "antmicropower:+3V3")
		(at 205.74 261.62 0)
		(unit 1)
		(exclude_from_sim no)
		(in_bom yes)
		(on_board yes)
		(dnp no)
		(fields_autoplaced yes)
		(property "Reference" "#PWR0346"
			(at 220.98 261.62 0)
			(effects
				(font
					(size 1.27 1.27)
					(thickness 0.15)
				)
				(justify left bottom)
				(hide yes)
			)
		)
		(property "Value" "+3V3"
			(at 205.74 256.54 0)
			(effects
				(font
					(size 1.27 1.27)
					(thickness 0.15)
				)
			)
		)
		(property "Footprint" ""
			(at 220.98 269.24 0)
			(effects
				(font
					(size 1.27 1.27)
					(thickness 0.15)
				)
				(justify left bottom)
				(hide yes)
			)
		)
		(property "Datasheet" ""
			(at 220.98 271.78 0)
			(effects
				(font
					(size 1.27 1.27)
					(thickness 0.15)
				)
				(justify left bottom)
				(hide yes)
			)
		)
		(property "Description" ""
			(at 205.74 261.62 0)
			(effects
				(font
					(size 1.27 1.27)
				)
				(hide yes)
			)
		)
		(property "Author" "Antmicro"
			(at 220.98 264.16 0)
			(effects
				(font
					(size 1.27 1.27)
					(thickness 0.15)
				)
				(justify left bottom)
				(hide yes)
			)
		)
		(property "License" "Apache-2.0"
			(at 220.98 266.7 0)
			(effects
				(font
					(size 1.27 1.27)
					(thickness 0.15)
				)
				(justify left bottom)
				(hide yes)
			)
		)
		(pin "1"
		)
		(instances
			(project "jetson-agx-thor-baseboard"
				(path ""
					(reference "#PWR0346")
					(unit 1)
				)
			)
		)
	)
	(symbol
		(lib_id "antmicroCapacitors0402:C_100n_0402")
		(at 287.02 85.09 0)
		(mirror x)
		(unit 1)
		(exclude_from_sim no)
		(in_bom yes)
		(on_board yes)
		(dnp no)
		(property "Reference" "C331"
			(at 295.656 83.82 0)
			(effects
				(font
					(size 1.27 1.27)
				)
				(justify right)
			)
		)
		(property "Value" "C_100n_0402"
			(at 307.34 74.93 0)
			(effects
				(font
					(size 1.27 1.27)
					(thickness 0.15)
				)
				(justify left bottom)
				(hide yes)
			)
		)
		(property "Footprint" "antmicro-footprints:C_0402_1005Metric"
			(at 307.34 72.39 0)
			(effects
				(font
					(size 1.27 1.27)
					(thickness 0.15)
				)
				(justify left bottom)
				(hide yes)
			)
		)
		(property "Datasheet" "https://www.murata.com/products/productdetail?partno=GRM155R61H104KE14%23"
			(at 307.34 69.85 0)
			(effects
				(font
					(size 1.27 1.27)
					(thickness 0.15)
				)
				(justify left bottom)
				(hide yes)
			)
		)
		(property "Description" "SMD Multilayer Ceramic Capacitor, 0.1 µF, 50 V, 0402 [1005 Metric], ± 10%, X5R, GRM Series"
			(at 287.02 85.09 0)
			(effects
				(font
					(size 1.27 1.27)
				)
				(hide yes)
			)
		)
		(property "Manufacturer" "Murata"
			(at 307.34 64.77 0)
			(effects
				(font
					(size 1.27 1.27)
					(thickness 0.15)
				)
				(justify left bottom)
				(hide yes)
			)
		)
		(property "MPN" "GRM155R61H104KE14D"
			(at 307.34 67.31 0)
			(effects
				(font
					(size 1.27 1.27)
					(thickness 0.15)
				)
				(justify left bottom)
				(hide yes)
			)
		)
		(property "Val" "100n"
			(at 288.544 84.074 0)
			(effects
				(font
					(size 1.27 1.27)
					(thickness 0.15)
				)
				(justify right)
			)
		)
		(property "License" "Apache-2.0"
			(at 307.34 62.23 0)
			(effects
				(font
					(size 1.27 1.27)
					(thickness 0.15)
				)
				(justify left bottom)
				(hide yes)
			)
		)
		(property "Author" "Antmicro"
			(at 307.34 59.69 0)
			(effects
				(font
					(size 1.27 1.27)
					(thickness 0.15)
				)
				(justify left bottom)
				(hide yes)
			)
		)
		(property "Voltage" "50V"
			(at 307.34 57.15 0)
			(effects
				(font
					(size 1.27 1.27)
				)
				(justify left bottom)
				(hide yes)
			)
		)
		(property "Dielectric" "X5R"
			(at 307.34 54.61 0)
			(effects
				(font
					(size 1.27 1.27)
				)
				(justify left bottom)
				(hide yes)
			)
		)
		(pin "1"
		)
		(pin "2"
		)
		(instances
			(project "jetson-agx-thor-baseboard"
				(path ""
					(reference "C331")
					(unit 1)
				)
			)
		)
	)
	(symbol
		(lib_id "antmicroCapacitors0402:C_100n_0402")
		(at 279.4 82.55 0)
		(mirror x)
		(unit 1)
		(exclude_from_sim no)
		(in_bom yes)
		(on_board yes)
		(dnp no)
		(property "Reference" "C327"
			(at 288.29 81.28 0)
			(effects
				(font
					(size 1.27 1.27)
				)
				(justify right)
			)
		)
		(property "Value" "C_100n_0402"
			(at 299.72 72.39 0)
			(effects
				(font
					(size 1.27 1.27)
					(thickness 0.15)
				)
				(justify left bottom)
				(hide yes)
			)
		)
		(property "Footprint" "antmicro-footprints:C_0402_1005Metric"
			(at 299.72 69.85 0)
			(effects
				(font
					(size 1.27 1.27)
					(thickness 0.15)
				)
				(justify left bottom)
				(hide yes)
			)
		)
		(property "Datasheet" "https://www.murata.com/products/productdetail?partno=GRM155R61H104KE14%23"
			(at 299.72 67.31 0)
			(effects
				(font
					(size 1.27 1.27)
					(thickness 0.15)
				)
				(justify left bottom)
				(hide yes)
			)
		)
		(property "Description" "SMD Multilayer Ceramic Capacitor, 0.1 µF, 50 V, 0402 [1005 Metric], ± 10%, X5R, GRM Series"
			(at 279.4 82.55 0)
			(effects
				(font
					(size 1.27 1.27)
				)
				(hide yes)
			)
		)
		(property "Manufacturer" "Murata"
			(at 299.72 62.23 0)
			(effects
				(font
					(size 1.27 1.27)
					(thickness 0.15)
				)
				(justify left bottom)
				(hide yes)
			)
		)
		(property "MPN" "GRM155R61H104KE14D"
			(at 299.72 64.77 0)
			(effects
				(font
					(size 1.27 1.27)
					(thickness 0.15)
				)
				(justify left bottom)
				(hide yes)
			)
		)
		(property "Val" "100n"
			(at 280.924 81.534 0)
			(effects
				(font
					(size 1.27 1.27)
					(thickness 0.15)
				)
				(justify right)
			)
		)
		(property "License" "Apache-2.0"
			(at 299.72 59.69 0)
			(effects
				(font
					(size 1.27 1.27)
					(thickness 0.15)
				)
				(justify left bottom)
				(hide yes)
			)
		)
		(property "Author" "Antmicro"
			(at 299.72 57.15 0)
			(effects
				(font
					(size 1.27 1.27)
					(thickness 0.15)
				)
				(justify left bottom)
				(hide yes)
			)
		)
		(property "Voltage" "50V"
			(at 299.72 54.61 0)
			(effects
				(font
					(size 1.27 1.27)
				)
				(justify left bottom)
				(hide yes)
			)
		)
		(property "Dielectric" "X5R"
			(at 299.72 52.07 0)
			(effects
				(font
					(size 1.27 1.27)
				)
				(justify left bottom)
				(hide yes)
			)
		)
		(pin "1"
		)
		(pin "2"
		)
		(instances
			(project "jetson-agx-thor-baseboard"
				(path ""
					(reference "C327")
					(unit 1)
				)
			)
		)
	)
	(symbol
		(lib_id "antmicroCapacitors0402:C_100n_0402")
		(at 279.4 97.79 0)
		(mirror x)
		(unit 1)
		(exclude_from_sim no)
		(in_bom yes)
		(on_board yes)
		(dnp no)
		(property "Reference" "C335"
			(at 288.29 96.52 0)
			(effects
				(font
					(size 1.27 1.27)
				)
				(justify right)
			)
		)
		(property "Value" "C_100n_0402"
			(at 299.72 87.63 0)
			(effects
				(font
					(size 1.27 1.27)
					(thickness 0.15)
				)
				(justify left bottom)
				(hide yes)
			)
		)
		(property "Footprint" "antmicro-footprints:C_0402_1005Metric"
			(at 299.72 85.09 0)
			(effects
				(font
					(size 1.27 1.27)
					(thickness 0.15)
				)
				(justify left bottom)
				(hide yes)
			)
		)
		(property "Datasheet" "https://www.murata.com/products/productdetail?partno=GRM155R61H104KE14%23"
			(at 299.72 82.55 0)
			(effects
				(font
					(size 1.27 1.27)
					(thickness 0.15)
				)
				(justify left bottom)
				(hide yes)
			)
		)
		(property "Description" "SMD Multilayer Ceramic Capacitor, 0.1 µF, 50 V, 0402 [1005 Metric], ± 10%, X5R, GRM Series"
			(at 279.4 97.79 0)
			(effects
				(font
					(size 1.27 1.27)
				)
				(hide yes)
			)
		)
		(property "Manufacturer" "Murata"
			(at 299.72 77.47 0)
			(effects
				(font
					(size 1.27 1.27)
					(thickness 0.15)
				)
				(justify left bottom)
				(hide yes)
			)
		)
		(property "MPN" "GRM155R61H104KE14D"
			(at 299.72 80.01 0)
			(effects
				(font
					(size 1.27 1.27)
					(thickness 0.15)
				)
				(justify left bottom)
				(hide yes)
			)
		)
		(property "Val" "100n"
			(at 280.924 96.774 0)
			(effects
				(font
					(size 1.27 1.27)
					(thickness 0.15)
				)
				(justify right)
			)
		)
		(property "License" "Apache-2.0"
			(at 299.72 74.93 0)
			(effects
				(font
					(size 1.27 1.27)
					(thickness 0.15)
				)
				(justify left bottom)
				(hide yes)
			)
		)
		(property "Author" "Antmicro"
			(at 299.72 72.39 0)
			(effects
				(font
					(size 1.27 1.27)
					(thickness 0.15)
				)
				(justify left bottom)
				(hide yes)
			)
		)
		(property "Voltage" "50V"
			(at 299.72 69.85 0)
			(effects
				(font
					(size 1.27 1.27)
				)
				(justify left bottom)
				(hide yes)
			)
		)
		(property "Dielectric" "X5R"
			(at 299.72 67.31 0)
			(effects
				(font
					(size 1.27 1.27)
				)
				(justify left bottom)
				(hide yes)
			)
		)
		(pin "1"
		)
		(pin "2"
		)
		(instances
			(project "jetson-agx-thor-baseboard"
				(path ""
					(reference "C335")
					(unit 1)
				)
			)
		)
	)
	(symbol
		(lib_id "antmicroLogicTranslatorsLevelShifters:TXU0304BQAR")
		(at 93.98 233.68 0)
		(mirror y)
		(unit 1)
		(exclude_from_sim no)
		(in_bom no)
		(on_board yes)
		(dnp yes)
		(fields_autoplaced yes)
		(property "Reference" "U59"
			(at 85.09 226.06 0)
			(effects
				(font
					(size 1.27 1.27)
					(thickness 0.15)
				)
			)
		)
		(property "Value" "TXU0304BQAR"
			(at 62.23 236.22 0)
			(effects
				(font
					(size 1.27 1.27)
					(thickness 0.15)
				)
				(justify left bottom)
				(hide yes)
			)
		)
		(property "Footprint" "antmicro-footprints:DHVQFN-14-1EP_2.5x3mm"
			(at 62.23 238.76 0)
			(effects
				(font
					(size 1.27 1.27)
					(thickness 0.15)
				)
				(justify left bottom)
				(hide yes)
			)
		)
		(property "Datasheet" "https://www.ti.com/lit/ds/symlink/txu0304.pdf?ts=1637748643258&ref_url=https%253A%252F%252Fwww.ti.com%252Fproduct%252FTXU0304"
			(at 62.23 241.3 0)
			(effects
				(font
					(size 1.27 1.27)
					(thickness 0.15)
				)
				(justify left bottom)
				(hide yes)
			)
		)
		(property "Description" "Logic translator/level shifter"
			(at 93.98 233.68 0)
			(effects
				(font
					(size 1.27 1.27)
				)
				(hide yes)
			)
		)
		(property "MPN" "TXU0304BQAR"
			(at 85.09 228.6 0)
			(effects
				(font
					(size 1.27 1.27)
					(thickness 0.15)
				)
			)
		)
		(property "Manufacturer" "Texas Instruments"
			(at 62.23 246.38 0)
			(effects
				(font
					(size 1.27 1.27)
					(thickness 0.15)
				)
				(justify left bottom)
				(hide yes)
			)
		)
		(property "Author" "Antmicro"
			(at 62.23 248.92 0)
			(effects
				(font
					(size 1.27 1.27)
					(thickness 0.15)
				)
				(justify left bottom)
				(hide yes)
			)
		)
		(property "License" "Apache-2.0"
			(at 62.23 251.46 0)
			(effects
				(font
					(size 1.27 1.27)
					(thickness 0.15)
				)
				(justify left bottom)
				(hide yes)
			)
		)
		(pin "9"
		)
		(pin "4"
		)
		(pin "7"
		)
		(pin "6"
		)
		(pin "10"
		)
		(pin "1"
		)
		(pin "8"
		)
		(pin "15"
		)
		(pin "3"
		)
		(pin "12"
		)
		(pin "13"
		)
		(pin "2"
		)
		(pin "5"
		)
		(pin "14"
		)
		(pin "11"
		)
		(instances
			(project "jetson-agx-thor-baseboard"
				(path ""
					(reference "U59")
					(unit 1)
				)
			)
		)
	)
	(symbol
		(lib_id "antmicropower:PWR_FLAG")
		(at 101.6 232.41 0)
		(mirror y)
		(unit 1)
		(exclude_from_sim no)
		(in_bom yes)
		(on_board yes)
		(dnp no)
		(fields_autoplaced yes)
		(property "Reference" "#FLG026"
			(at 101.6 230.505 0)
			(effects
				(font
					(size 1.27 1.27)
				)
				(hide yes)
			)
		)
		(property "Value" "PWR_FLAG"
			(at 101.6 227.33 0)
			(effects
				(font
					(size 1.27 1.27)
				)
			)
		)
		(property "Footprint" ""
			(at 101.6 232.41 0)
			(effects
				(font
					(size 1.27 1.27)
				)
				(hide yes)
			)
		)
		(property "Datasheet" ""
			(at 101.6 232.41 0)
			(effects
				(font
					(size 1.27 1.27)
				)
				(hide yes)
			)
		)
		(property "Description" ""
			(at 101.6 232.41 0)
			(effects
				(font
					(size 1.27 1.27)
				)
				(hide yes)
			)
		)
		(pin "1"
		)
		(instances
			(project "jetson-agx-thor-baseboard"
				(path ""
					(reference "#FLG026")
					(unit 1)
				)
			)
		)
	)
	(symbol
		(lib_id "antmicroCapacitors0402:C_100n_0402")
		(at 279.4 92.71 0)
		(mirror x)
		(unit 1)
		(exclude_from_sim no)
		(in_bom yes)
		(on_board yes)
		(dnp no)
		(property "Reference" "C334"
			(at 288.29 91.44 0)
			(effects
				(font
					(size 1.27 1.27)
				)
				(justify right)
			)
		)
		(property "Value" "C_100n_0402"
			(at 299.72 82.55 0)
			(effects
				(font
					(size 1.27 1.27)
					(thickness 0.15)
				)
				(justify left bottom)
				(hide yes)
			)
		)
		(property "Footprint" "antmicro-footprints:C_0402_1005Metric"
			(at 299.72 80.01 0)
			(effects
				(font
					(size 1.27 1.27)
					(thickness 0.15)
				)
				(justify left bottom)
				(hide yes)
			)
		)
		(property "Datasheet" "https://www.murata.com/products/productdetail?partno=GRM155R61H104KE14%23"
			(at 299.72 77.47 0)
			(effects
				(font
					(size 1.27 1.27)
					(thickness 0.15)
				)
				(justify left bottom)
				(hide yes)
			)
		)
		(property "Description" "SMD Multilayer Ceramic Capacitor, 0.1 µF, 50 V, 0402 [1005 Metric], ± 10%, X5R, GRM Series"
			(at 279.4 92.71 0)
			(effects
				(font
					(size 1.27 1.27)
				)
				(hide yes)
			)
		)
		(property "Manufacturer" "Murata"
			(at 299.72 72.39 0)
			(effects
				(font
					(size 1.27 1.27)
					(thickness 0.15)
				)
				(justify left bottom)
				(hide yes)
			)
		)
		(property "MPN" "GRM155R61H104KE14D"
			(at 299.72 74.93 0)
			(effects
				(font
					(size 1.27 1.27)
					(thickness 0.15)
				)
				(justify left bottom)
				(hide yes)
			)
		)
		(property "Val" "100n"
			(at 280.924 91.694 0)
			(effects
				(font
					(size 1.27 1.27)
					(thickness 0.15)
				)
				(justify right)
			)
		)
		(property "License" "Apache-2.0"
			(at 299.72 69.85 0)
			(effects
				(font
					(size 1.27 1.27)
					(thickness 0.15)
				)
				(justify left bottom)
				(hide yes)
			)
		)
		(property "Author" "Antmicro"
			(at 299.72 67.31 0)
			(effects
				(font
					(size 1.27 1.27)
					(thickness 0.15)
				)
				(justify left bottom)
				(hide yes)
			)
		)
		(property "Voltage" "50V"
			(at 299.72 64.77 0)
			(effects
				(font
					(size 1.27 1.27)
				)
				(justify left bottom)
				(hide yes)
			)
		)
		(property "Dielectric" "X5R"
			(at 299.72 62.23 0)
			(effects
				(font
					(size 1.27 1.27)
				)
				(justify left bottom)
				(hide yes)
			)
		)
		(pin "1"
		)
		(pin "2"
		)
		(instances
			(project "jetson-agx-thor-baseboard"
				(path ""
					(reference "C334")
					(unit 1)
				)
			)
		)
	)
	(symbol
		(lib_id "antmicroResistors0402:R_0R_0402")
		(at 62.23 246.38 0)
		(mirror y)
		(unit 1)
		(exclude_from_sim no)
		(in_bom no)
		(on_board yes)
		(dnp yes)
		(property "Reference" "R295"
			(at 64.77 245.11 0)
			(effects
				(font
					(size 1.27 1.27)
					(thickness 0.15)
				)
			)
		)
		(property "Value" "R_0R_0402"
			(at 41.91 259.08 0)
			(effects
				(font
					(size 1.27 1.27)
					(thickness 0.15)
				)
				(justify left bottom)
				(hide yes)
			)
		)
		(property "Footprint" "antmicro-footprints:R_0402_1005Metric"
			(at 41.91 261.62 0)
			(effects
				(font
					(size 1.27 1.27)
					(thickness 0.15)
				)
				(justify left bottom)
				(hide yes)
			)
		)
		(property "Datasheet" "https://industrial.panasonic.com/cdbs/www-data/pdf/RDA0000/AOA0000C301.pdf"
			(at 41.91 264.16 0)
			(effects
				(font
					(size 1.27 1.27)
					(thickness 0.15)
				)
				(justify left bottom)
				(hide yes)
			)
		)
		(property "Description" "SMD Chip Resistor, Jumper, 0 ohm, 100 mW, 0402 [1005 Metric], Thick Film, General Purpose"
			(at 62.23 246.38 0)
			(effects
				(font
					(size 1.27 1.27)
				)
				(hide yes)
			)
		)
		(property "MPN" "ERJ2GE0R00X"
			(at 41.91 266.7 0)
			(effects
				(font
					(size 1.27 1.27)
					(thickness 0.15)
				)
				(justify left bottom)
				(hide yes)
			)
		)
		(property "Manufacturer" "Panasonic"
			(at 41.91 269.24 0)
			(effects
				(font
					(size 1.27 1.27)
					(thickness 0.15)
				)
				(justify left bottom)
				(hide yes)
			)
		)
		(property "License" "Apache-2.0"
			(at 41.91 271.78 0)
			(effects
				(font
					(size 1.27 1.27)
					(thickness 0.15)
				)
				(justify left bottom)
				(hide yes)
			)
		)
		(property "Author" "Antmicro"
			(at 41.91 274.32 0)
			(effects
				(font
					(size 1.27 1.27)
					(thickness 0.15)
				)
				(justify left bottom)
				(hide yes)
			)
		)
		(property "Val" "0R"
			(at 55.88 245.11 0)
			(effects
				(font
					(size 1.27 1.27)
					(thickness 0.15)
				)
			)
		)
		(property "Tolerance" "~"
			(at 41.91 256.54 0)
			(effects
				(font
					(size 1.27 1.27)
				)
				(justify left bottom)
				(hide yes)
			)
		)
		(property "Current" "1A"
			(at 41.91 276.86 0)
			(effects
				(font
					(size 1.27 1.27)
					(thickness 0.15)
				)
				(justify left bottom)
				(hide yes)
			)
		)
		(pin "2"
		)
		(pin "1"
		)
		(instances
			(project "jetson-agx-thor-baseboard"
				(path ""
					(reference "R295")
					(unit 1)
				)
			)
		)
	)
	(symbol
		(lib_id "antmicroCapacitors0402:C_100n_0402")
		(at 287.02 110.49 0)
		(mirror x)
		(unit 1)
		(exclude_from_sim no)
		(in_bom yes)
		(on_board yes)
		(dnp no)
		(property "Reference" "C341"
			(at 295.656 109.22 0)
			(effects
				(font
					(size 1.27 1.27)
				)
				(justify right)
			)
		)
		(property "Value" "C_100n_0402"
			(at 307.34 100.33 0)
			(effects
				(font
					(size 1.27 1.27)
					(thickness 0.15)
				)
				(justify left bottom)
				(hide yes)
			)
		)
		(property "Footprint" "antmicro-footprints:C_0402_1005Metric"
			(at 307.34 97.79 0)
			(effects
				(font
					(size 1.27 1.27)
					(thickness 0.15)
				)
				(justify left bottom)
				(hide yes)
			)
		)
		(property "Datasheet" "https://www.murata.com/products/productdetail?partno=GRM155R61H104KE14%23"
			(at 307.34 95.25 0)
			(effects
				(font
					(size 1.27 1.27)
					(thickness 0.15)
				)
				(justify left bottom)
				(hide yes)
			)
		)
		(property "Description" "SMD Multilayer Ceramic Capacitor, 0.1 µF, 50 V, 0402 [1005 Metric], ± 10%, X5R, GRM Series"
			(at 287.02 110.49 0)
			(effects
				(font
					(size 1.27 1.27)
				)
				(hide yes)
			)
		)
		(property "Manufacturer" "Murata"
			(at 307.34 90.17 0)
			(effects
				(font
					(size 1.27 1.27)
					(thickness 0.15)
				)
				(justify left bottom)
				(hide yes)
			)
		)
		(property "MPN" "GRM155R61H104KE14D"
			(at 307.34 92.71 0)
			(effects
				(font
					(size 1.27 1.27)
					(thickness 0.15)
				)
				(justify left bottom)
				(hide yes)
			)
		)
		(property "Val" "100n"
			(at 288.544 109.474 0)
			(effects
				(font
					(size 1.27 1.27)
					(thickness 0.15)
				)
				(justify right)
			)
		)
		(property "License" "Apache-2.0"
			(at 307.34 87.63 0)
			(effects
				(font
					(size 1.27 1.27)
					(thickness 0.15)
				)
				(justify left bottom)
				(hide yes)
			)
		)
		(property "Author" "Antmicro"
			(at 307.34 85.09 0)
			(effects
				(font
					(size 1.27 1.27)
					(thickness 0.15)
				)
				(justify left bottom)
				(hide yes)
			)
		)
		(property "Voltage" "50V"
			(at 307.34 82.55 0)
			(effects
				(font
					(size 1.27 1.27)
				)
				(justify left bottom)
				(hide yes)
			)
		)
		(property "Dielectric" "X5R"
			(at 307.34 80.01 0)
			(effects
				(font
					(size 1.27 1.27)
				)
				(justify left bottom)
				(hide yes)
			)
		)
		(pin "1"
		)
		(pin "2"
		)
		(instances
			(project "jetson-agx-thor-baseboard"
				(path ""
					(reference "C341")
					(unit 1)
				)
			)
		)
	)
	(symbol
		(lib_id "antmicroCapacitors0402:C_100n_0402")
		(at 287.02 130.81 0)
		(mirror x)
		(unit 1)
		(exclude_from_sim no)
		(in_bom yes)
		(on_board yes)
		(dnp no)
		(property "Reference" "C350"
			(at 295.656 129.54 0)
			(effects
				(font
					(size 1.27 1.27)
				)
				(justify right)
			)
		)
		(property "Value" "C_100n_0402"
			(at 307.34 120.65 0)
			(effects
				(font
					(size 1.27 1.27)
					(thickness 0.15)
				)
				(justify left bottom)
				(hide yes)
			)
		)
		(property "Footprint" "antmicro-footprints:C_0402_1005Metric"
			(at 307.34 118.11 0)
			(effects
				(font
					(size 1.27 1.27)
					(thickness 0.15)
				)
				(justify left bottom)
				(hide yes)
			)
		)
		(property "Datasheet" "https://www.murata.com/products/productdetail?partno=GRM155R61H104KE14%23"
			(at 307.34 115.57 0)
			(effects
				(font
					(size 1.27 1.27)
					(thickness 0.15)
				)
				(justify left bottom)
				(hide yes)
			)
		)
		(property "Description" "SMD Multilayer Ceramic Capacitor, 0.1 µF, 50 V, 0402 [1005 Metric], ± 10%, X5R, GRM Series"
			(at 287.02 130.81 0)
			(effects
				(font
					(size 1.27 1.27)
				)
				(hide yes)
			)
		)
		(property "Manufacturer" "Murata"
			(at 307.34 110.49 0)
			(effects
				(font
					(size 1.27 1.27)
					(thickness 0.15)
				)
				(justify left bottom)
				(hide yes)
			)
		)
		(property "MPN" "GRM155R61H104KE14D"
			(at 307.34 113.03 0)
			(effects
				(font
					(size 1.27 1.27)
					(thickness 0.15)
				)
				(justify left bottom)
				(hide yes)
			)
		)
		(property "Val" "100n"
			(at 288.544 129.794 0)
			(effects
				(font
					(size 1.27 1.27)
					(thickness 0.15)
				)
				(justify right)
			)
		)
		(property "License" "Apache-2.0"
			(at 307.34 107.95 0)
			(effects
				(font
					(size 1.27 1.27)
					(thickness 0.15)
				)
				(justify left bottom)
				(hide yes)
			)
		)
		(property "Author" "Antmicro"
			(at 307.34 105.41 0)
			(effects
				(font
					(size 1.27 1.27)
					(thickness 0.15)
				)
				(justify left bottom)
				(hide yes)
			)
		)
		(property "Voltage" "50V"
			(at 307.34 102.87 0)
			(effects
				(font
					(size 1.27 1.27)
				)
				(justify left bottom)
				(hide yes)
			)
		)
		(property "Dielectric" "X5R"
			(at 307.34 100.33 0)
			(effects
				(font
					(size 1.27 1.27)
				)
				(justify left bottom)
				(hide yes)
			)
		)
		(pin "1"
		)
		(pin "2"
		)
		(instances
			(project "jetson-agx-thor-baseboard"
				(path ""
					(reference "C350")
					(unit 1)
				)
			)
		)
	)
	(symbol
		(lib_id "antmicropower:GND")
		(at 222.25 241.3 0)
		(mirror y)
		(unit 1)
		(exclude_from_sim no)
		(in_bom yes)
		(on_board yes)
		(dnp no)
		(property "Reference" "#PWR030"
			(at 222.25 247.65 0)
			(effects
				(font
					(size 1.27 1.27)
				)
				(justify left bottom)
				(hide yes)
			)
		)
		(property "Value" "GND"
			(at 222.25 245.11 0)
			(effects
				(font
					(size 1.27 1.27)
				)
			)
		)
		(property "Footprint" ""
			(at 222.25 241.3 0)
			(effects
				(font
					(size 1.27 1.27)
				)
				(justify left bottom)
				(hide yes)
			)
		)
		(property "Datasheet" ""
			(at 222.25 241.3 0)
			(effects
				(font
					(size 1.27 1.27)
				)
				(justify left bottom)
				(hide yes)
			)
		)
		(property "Description" ""
			(at 222.25 241.3 0)
			(effects
				(font
					(size 1.27 1.27)
				)
				(hide yes)
			)
		)
		(property "Author" "Antmicro"
			(at 213.36 248.92 0)
			(effects
				(font
					(size 1.27 1.27)
					(thickness 0.15)
				)
				(justify left bottom)
				(hide yes)
			)
		)
		(property "License" "Apache-2.0"
			(at 213.36 251.46 0)
			(effects
				(font
					(size 1.27 1.27)
					(thickness 0.15)
				)
				(justify left bottom)
				(hide yes)
			)
		)
		(pin "1"
		)
		(instances
			(project "jetson-agx-thor-baseboard"
				(path ""
					(reference "#PWR030")
					(unit 1)
				)
			)
		)
	)
	(symbol
		(lib_id "antmicroResistors0402:R_49R9_0402")
		(at 274.32 245.11 90)
		(unit 1)
		(exclude_from_sim no)
		(in_bom yes)
		(on_board yes)
		(dnp no)
		(property "Reference" "R5"
			(at 275.59 241.3 90)
			(effects
				(font
					(size 1.27 1.27)
					(thickness 0.15)
				)
				(justify right)
			)
		)
		(property "Value" "R_49R9_0402"
			(at 287.02 224.79 0)
			(effects
				(font
					(size 1.27 1.27)
					(thickness 0.15)
				)
				(justify left bottom)
				(hide yes)
			)
		)
		(property "Footprint" "antmicro-footprints:R_0402_1005Metric"
			(at 289.56 224.79 0)
			(effects
				(font
					(size 1.27 1.27)
					(thickness 0.15)
				)
				(justify left bottom)
				(hide yes)
			)
		)
		(property "Datasheet" "https://www.bourns.com/docs/product-datasheets/cr.pdf"
			(at 292.1 224.79 0)
			(effects
				(font
					(size 1.27 1.27)
					(thickness 0.15)
				)
				(justify left bottom)
				(hide yes)
			)
		)
		(property "Description" "SMD Chip Resistor, 49.9 ohm, ± 1%, 62.5 mW, 0402 [1005 Metric], Thick Film, General Purpose"
			(at 274.32 245.11 0)
			(effects
				(font
					(size 1.27 1.27)
				)
				(hide yes)
			)
		)
		(property "MPN" "CR0402-FX-49R9GLF"
			(at 294.64 224.79 0)
			(effects
				(font
					(size 1.27 1.27)
					(thickness 0.15)
				)
				(justify left bottom)
				(hide yes)
			)
		)
		(property "Manufacturer" "Bourns"
			(at 297.18 224.79 0)
			(effects
				(font
					(size 1.27 1.27)
					(thickness 0.15)
				)
				(justify left bottom)
				(hide yes)
			)
		)
		(property "License" "Apache-2.0"
			(at 299.72 224.79 0)
			(effects
				(font
					(size 1.27 1.27)
					(thickness 0.15)
				)
				(justify left bottom)
				(hide yes)
			)
		)
		(property "Author" "Antmicro"
			(at 302.26 224.79 0)
			(effects
				(font
					(size 1.27 1.27)
					(thickness 0.15)
				)
				(justify left bottom)
				(hide yes)
			)
		)
		(property "Val" "49R9"
			(at 275.59 243.84 90)
			(effects
				(font
					(size 1.27 1.27)
					(thickness 0.15)
				)
				(justify right)
			)
		)
		(property "Tolerance" "1%"
			(at 284.48 224.79 0)
			(effects
				(font
					(size 1.27 1.27)
				)
				(justify left bottom)
				(hide yes)
			)
		)
		(pin "1"
		)
		(pin "2"
		)
		(instances
			(project "jetson-agx-thor-baseboard"
				(path ""
					(reference "R5")
					(unit 1)
				)
			)
		)
	)
	(symbol
		(lib_id "antmicroResistors0402:R_0R_0402")
		(at 62.23 241.3 0)
		(mirror y)
		(unit 1)
		(exclude_from_sim no)
		(in_bom no)
		(on_board yes)
		(dnp yes)
		(property "Reference" "R293"
			(at 64.77 240.03 0)
			(effects
				(font
					(size 1.27 1.27)
					(thickness 0.15)
				)
			)
		)
		(property "Value" "R_0R_0402"
			(at 41.91 254 0)
			(effects
				(font
					(size 1.27 1.27)
					(thickness 0.15)
				)
				(justify left bottom)
				(hide yes)
			)
		)
		(property "Footprint" "antmicro-footprints:R_0402_1005Metric"
			(at 41.91 256.54 0)
			(effects
				(font
					(size 1.27 1.27)
					(thickness 0.15)
				)
				(justify left bottom)
				(hide yes)
			)
		)
		(property "Datasheet" "https://industrial.panasonic.com/cdbs/www-data/pdf/RDA0000/AOA0000C301.pdf"
			(at 41.91 259.08 0)
			(effects
				(font
					(size 1.27 1.27)
					(thickness 0.15)
				)
				(justify left bottom)
				(hide yes)
			)
		)
		(property "Description" "SMD Chip Resistor, Jumper, 0 ohm, 100 mW, 0402 [1005 Metric], Thick Film, General Purpose"
			(at 62.23 241.3 0)
			(effects
				(font
					(size 1.27 1.27)
				)
				(hide yes)
			)
		)
		(property "MPN" "ERJ2GE0R00X"
			(at 41.91 261.62 0)
			(effects
				(font
					(size 1.27 1.27)
					(thickness 0.15)
				)
				(justify left bottom)
				(hide yes)
			)
		)
		(property "Manufacturer" "Panasonic"
			(at 41.91 264.16 0)
			(effects
				(font
					(size 1.27 1.27)
					(thickness 0.15)
				)
				(justify left bottom)
				(hide yes)
			)
		)
		(property "License" "Apache-2.0"
			(at 41.91 266.7 0)
			(effects
				(font
					(size 1.27 1.27)
					(thickness 0.15)
				)
				(justify left bottom)
				(hide yes)
			)
		)
		(property "Author" "Antmicro"
			(at 41.91 269.24 0)
			(effects
				(font
					(size 1.27 1.27)
					(thickness 0.15)
				)
				(justify left bottom)
				(hide yes)
			)
		)
		(property "Val" "0R"
			(at 55.88 240.03 0)
			(effects
				(font
					(size 1.27 1.27)
					(thickness 0.15)
				)
			)
		)
		(property "Tolerance" "~"
			(at 41.91 251.46 0)
			(effects
				(font
					(size 1.27 1.27)
				)
				(justify left bottom)
				(hide yes)
			)
		)
		(property "Current" "1A"
			(at 41.91 271.78 0)
			(effects
				(font
					(size 1.27 1.27)
					(thickness 0.15)
				)
				(justify left bottom)
				(hide yes)
			)
		)
		(pin "2"
		)
		(pin "1"
		)
		(instances
			(project "jetson-agx-thor-baseboard"
				(path ""
					(reference "R293")
					(unit 1)
				)
			)
		)
	)
	(symbol
		(lib_id "antmicroCapacitors0402:C_100n_0402")
		(at 373.38 59.69 0)
		(mirror x)
		(unit 1)
		(exclude_from_sim no)
		(in_bom yes)
		(on_board yes)
		(dnp no)
		(property "Reference" "C323"
			(at 382.016 58.42 0)
			(effects
				(font
					(size 1.27 1.27)
				)
				(justify right)
			)
		)
		(property "Value" "C_100n_0402"
			(at 393.7 49.53 0)
			(effects
				(font
					(size 1.27 1.27)
					(thickness 0.15)
				)
				(justify left bottom)
				(hide yes)
			)
		)
		(property "Footprint" "antmicro-footprints:C_0402_1005Metric"
			(at 393.7 46.99 0)
			(effects
				(font
					(size 1.27 1.27)
					(thickness 0.15)
				)
				(justify left bottom)
				(hide yes)
			)
		)
		(property "Datasheet" "https://www.murata.com/products/productdetail?partno=GRM155R61H104KE14%23"
			(at 393.7 44.45 0)
			(effects
				(font
					(size 1.27 1.27)
					(thickness 0.15)
				)
				(justify left bottom)
				(hide yes)
			)
		)
		(property "Description" "SMD Multilayer Ceramic Capacitor, 0.1 µF, 50 V, 0402 [1005 Metric], ± 10%, X5R, GRM Series"
			(at 373.38 59.69 0)
			(effects
				(font
					(size 1.27 1.27)
				)
				(hide yes)
			)
		)
		(property "Manufacturer" "Murata"
			(at 393.7 39.37 0)
			(effects
				(font
					(size 1.27 1.27)
					(thickness 0.15)
				)
				(justify left bottom)
				(hide yes)
			)
		)
		(property "MPN" "GRM155R61H104KE14D"
			(at 393.7 41.91 0)
			(effects
				(font
					(size 1.27 1.27)
					(thickness 0.15)
				)
				(justify left bottom)
				(hide yes)
			)
		)
		(property "Val" "100n"
			(at 374.904 58.674 0)
			(effects
				(font
					(size 1.27 1.27)
					(thickness 0.15)
				)
				(justify right)
			)
		)
		(property "License" "Apache-2.0"
			(at 393.7 36.83 0)
			(effects
				(font
					(size 1.27 1.27)
					(thickness 0.15)
				)
				(justify left bottom)
				(hide yes)
			)
		)
		(property "Author" "Antmicro"
			(at 393.7 34.29 0)
			(effects
				(font
					(size 1.27 1.27)
					(thickness 0.15)
				)
				(justify left bottom)
				(hide yes)
			)
		)
		(property "Voltage" "50V"
			(at 393.7 31.75 0)
			(effects
				(font
					(size 1.27 1.27)
				)
				(justify left bottom)
				(hide yes)
			)
		)
		(property "Dielectric" "X5R"
			(at 393.7 29.21 0)
			(effects
				(font
					(size 1.27 1.27)
				)
				(justify left bottom)
				(hide yes)
			)
		)
		(pin "1"
		)
		(pin "2"
		)
		(instances
			(project "jetson-agx-thor-baseboard"
				(path ""
					(reference "C323")
					(unit 1)
				)
			)
		)
	)
	(symbol
		(lib_id "antmicroResistors0402:R_100k_0402")
		(at 213.36 237.49 0)
		(unit 1)
		(exclude_from_sim no)
		(in_bom yes)
		(on_board yes)
		(dnp no)
		(property "Reference" "R1"
			(at 212.598 236.22 0)
			(effects
				(font
					(size 1.27 1.27)
					(thickness 0.15)
				)
			)
		)
		(property "Value" "R_100k_0402"
			(at 233.68 250.19 0)
			(effects
				(font
					(size 1.27 1.27)
					(thickness 0.15)
				)
				(justify left bottom)
				(hide yes)
			)
		)
		(property "Footprint" "antmicro-footprints:R_0402_1005Metric"
			(at 233.68 252.73 0)
			(effects
				(font
					(size 1.27 1.27)
					(thickness 0.15)
				)
				(justify left bottom)
				(hide yes)
			)
		)
		(property "Datasheet" "https://www.bourns.com/docs/product-datasheets/cr.pdf"
			(at 233.68 255.27 0)
			(effects
				(font
					(size 1.27 1.27)
					(thickness 0.15)
				)
				(justify left bottom)
				(hide yes)
			)
		)
		(property "Description" "SMD Chip Resistor, 100 kohm, ± 1%, 62.5 mW, 0402 [1005 Metric], Thick Film, General Purpose"
			(at 213.36 237.49 0)
			(effects
				(font
					(size 1.27 1.27)
				)
				(hide yes)
			)
		)
		(property "MPN" "CR0402-FX-1003GLF"
			(at 233.68 257.81 0)
			(effects
				(font
					(size 1.27 1.27)
					(thickness 0.15)
				)
				(justify left bottom)
				(hide yes)
			)
		)
		(property "Manufacturer" "Bourns"
			(at 233.68 260.35 0)
			(effects
				(font
					(size 1.27 1.27)
					(thickness 0.15)
				)
				(justify left bottom)
				(hide yes)
			)
		)
		(property "License" "Apache-2.0"
			(at 233.68 262.89 0)
			(effects
				(font
					(size 1.27 1.27)
					(thickness 0.15)
				)
				(justify left bottom)
				(hide yes)
			)
		)
		(property "Author" "Antmicro"
			(at 233.68 265.43 0)
			(effects
				(font
					(size 1.27 1.27)
					(thickness 0.15)
				)
				(justify left bottom)
				(hide yes)
			)
		)
		(property "Val" "100k"
			(at 220.472 236.22 0)
			(effects
				(font
					(size 1.27 1.27)
					(thickness 0.15)
				)
			)
		)
		(property "Tolerance" "1%"
			(at 233.68 247.65 0)
			(effects
				(font
					(size 1.27 1.27)
				)
				(justify left bottom)
				(hide yes)
			)
		)
		(pin "1"
		)
		(pin "2"
		)
		(instances
			(project ""
				(path ""
					(reference "R1")
					(unit 1)
				)
			)
		)
	)
	(symbol
		(lib_id "antmicroB2BConnectors:Hermaphroditic_Molex_203456-0003_CUSTOM_Jetson_AGX_Thor_H8mm")
		(at 78.74 33.02 0)
		(unit 3)
		(exclude_from_sim no)
		(in_bom yes)
		(on_board yes)
		(dnp no)
		(fields_autoplaced yes)
		(property "Reference" "J1"
			(at 103.505 25.4 0)
			(effects
				(font
					(size 1.27 1.27)
				)
			)
		)
		(property "Value" "Hermaphroditic_Molex_203456-0003_CUSTOM_Jetson_AGX_Thor_H8mm"
			(at 155.194 39.116 0)
			(effects
				(font
					(size 1.27 1.27)
				)
				(justify left bottom)
				(hide yes)
			)
		)
		(property "Footprint" "antmicro-footprints:Conn_Hermaphroditic_Molex_203456-0003_mirrored"
			(at 155.194 41.402 0)
			(effects
				(font
					(size 1.27 1.27)
				)
				(justify left bottom)
				(hide yes)
			)
		)
		(property "Datasheet" "https://www.molex.com/content/dam/molex/molex-dot-com/products/automated/en-us/salesdrawingpdf/203/203456/2034560003_sd.pdf?inline"
			(at 155.194 43.688 0)
			(effects
				(font
					(size 1.27 1.27)
				)
				(justify left bottom)
				(hide yes)
			)
		)
		(property "Description" "Mirror Mezz Hermaphroditic Connector, 5.50mm Connector Height, BGA-Attach Mounting, 7 Pair, 11 Row, 699 Circuits, 0.76µm Gold Plating, without Pegs"
			(at 155.194 52.324 0)
			(effects
				(font
					(size 1.27 1.27)
				)
				(justify left bottom)
				(hide yes)
			)
		)
		(property "MPN" "203456-0003"
			(at 103.505 27.94 0)
			(effects
				(font
					(size 1.27 1.27)
				)
			)
		)
		(property "Manufacturer" "Molex"
			(at 155.194 45.974 0)
			(effects
				(font
					(size 1.27 1.27)
				)
				(justify left bottom)
				(hide yes)
			)
		)
		(property "Author" "Antmicro"
			(at 155.194 48.006 0)
			(effects
				(font
					(size 1.27 1.27)
				)
				(justify left bottom)
				(hide yes)
			)
		)
		(property "License" "Apache-2.0"
			(at 155.194 50.038 0)
			(effects
				(font
					(size 1.27 1.27)
				)
				(justify left bottom)
				(hide yes)
			)
		)
		(pin "J37"
		)
		(pin "D37"
		)
		(pin "C40"
		)
		(pin "J40"
		)
		(pin "C30"
		)
		(pin "D28"
		)
		(pin "F57"
		)
		(pin "F45"
		)
		(pin "B48"
		)
		(pin "F46"
		)
		(pin "C41"
		)
		(pin "D23"
		)
		(pin "G48"
		)
		(pin "C42"
		)
		(pin "J5"
		)
		(pin "E56"
		)
		(pin "D27"
		)
		(pin "C27"
		)
		(pin "E28"
		)
		(pin "D63"
		)
		(pin "A40"
		)
		(pin "J21"
		)
		(pin "L24"
		)
		(pin "L59"
		)
		(pin "B27"
		)
		(pin "D1"
		)
		(pin "C16"
		)
		(pin "H12"
		)
		(pin "H19"
		)
		(pin "F9"
		)
		(pin "A42"
		)
		(pin "A41"
		)
		(pin "B42"
		)
		(pin "E7"
		)
		(pin "B43"
		)
		(pin "L54"
		)
		(pin "A57"
		)
		(pin "J42"
		)
		(pin "B12"
		)
		(pin "F63"
		)
		(pin "J38"
		)
		(pin "J41"
		)
		(pin "L43"
		)
		(pin "D59"
		)
		(pin "J65"
		)
		(pin "H26"
		)
		(pin "G19"
		)
		(pin "G7"
		)
		(pin "D12"
		)
		(pin "F34"
		)
		(pin "G42"
		)
		(pin "G41"
		)
		(pin "H42"
		)
		(pin "E30"
		)
		(pin "L62"
		)
		(pin "L49"
		)
		(pin "H43"
		)
		(pin "F27"
		)
		(pin "G64"
		)
		(pin "J54"
		)
		(pin "F39"
		)
		(pin "E38"
		)
		(pin "D8"
		)
		(pin "H30"
		)
		(pin "B33"
		)
		(pin "G12"
		)
		(pin "E39"
		)
		(pin "E5"
		)
		(pin "E41"
		)
		(pin "E42"
		)
		(pin "H16"
		)
		(pin "F42"
		)
		(pin "F43"
		)
		(pin "L56"
		)
		(pin "F21"
		)
		(pin "B21"
		)
		(pin "F20"
		)
		(pin "C19"
		)
		(pin "L15"
		)
		(pin "F50"
		)
		(pin "F37"
		)
		(pin "J60"
		)
		(pin "E18"
		)
		(pin "E64"
		)
		(pin "E19"
		)
		(pin "B13"
		)
		(pin "D9"
		)
		(pin "K56"
		)
		(pin "D5"
		)
		(pin "A19"
		)
		(pin "D45"
		)
		(pin "L12"
		)
		(pin "C47"
		)
		(pin "E13"
		)
		(pin "E46"
		)
		(pin "C24"
		)
		(pin "H64"
		)
		(pin "A24"
		)
		(pin "F3"
		)
		(pin "L27"
		)
		(pin "H40"
		)
		(pin "C20"
		)
		(pin "G13"
		)
		(pin "K29"
		)
		(pin "H65"
		)
		(pin "A9"
		)
		(pin "A13"
		)
		(pin "A30"
		)
		(pin "B34"
		)
		(pin "E12"
		)
		(pin "C11"
		)
		(pin "E23"
		)
		(pin "D7"
		)
		(pin "D18"
		)
		(pin "F65"
		)
		(pin "D53"
		)
		(pin "H35"
		)
		(pin "A25"
		)
		(pin "C3"
		)
		(pin "J33"
		)
		(pin "H39"
		)
		(pin "B50"
		)
		(pin "A63"
		)
		(pin "G65"
		)
		(pin "B22"
		)
		(pin "B18"
		)
		(pin "E57"
		)
		(pin "D29"
		)
		(pin "D19"
		)
		(pin "F25"
		)
		(pin "F28"
		)
		(pin "L10"
		)
		(pin "C31"
		)
		(pin "G1"
		)
		(pin "E16"
		)
		(pin "E40"
		)
		(pin "E20"
		)
		(pin "D50"
		)
		(pin "D57"
		)
		(pin "F59"
		)
		(pin "J64"
		)
		(pin "D49"
		)
		(pin "E62"
		)
		(pin "E24"
		)
		(pin "J26"
		)
		(pin "K25"
		)
		(pin "G26"
		)
		(pin "H29"
		)
		(pin "B29"
		)
		(pin "B38"
		)
		(pin "C10"
		)
		(pin "F12"
		)
		(pin "A46"
		)
		(pin "K12"
		)
		(pin "E17"
		)
		(pin "F16"
		)
		(pin "H25"
		)
		(pin "K16"
		)
		(pin "J30"
		)
		(pin "D17"
		)
		(pin "K37"
		)
		(pin "B5"
		)
		(pin "E50"
		)
		(pin "D16"
		)
		(pin "D4"
		)
		(pin "G40"
		)
		(pin "H7"
		)
		(pin "A45"
		)
		(pin "H45"
		)
		(pin "C18"
		)
		(pin "G36"
		)
		(pin "B58"
		)
		(pin "A10"
		)
		(pin "L52"
		)
		(pin "G54"
		)
		(pin "G53"
		)
		(pin "D20"
		)
		(pin "K50"
		)
		(pin "H61"
		)
		(pin "C54"
		)
		(pin "H33"
		)
		(pin "H51"
		)
		(pin "H62"
		)
		(pin "F44"
		)
		(pin "H32"
		)
		(pin "C6"
		)
		(pin "L25"
		)
		(pin "A35"
		)
		(pin "D55"
		)
		(pin "L9"
		)
		(pin "F41"
		)
		(pin "A56"
		)
		(pin "J18"
		)
		(pin "K7"
		)
		(pin "D13"
		)
		(pin "A34"
		)
		(pin "G33"
		)
		(pin "A38"
		)
		(pin "D24"
		)
		(pin "H63"
		)
		(pin "C58"
		)
		(pin "J35"
		)
		(pin "J51"
		)
		(pin "E61"
		)
		(pin "E25"
		)
		(pin "E29"
		)
		(pin "E63"
		)
		(pin "L60"
		)
		(pin "D62"
		)
		(pin "G58"
		)
		(pin "J12"
		)
		(pin "J59"
		)
		(pin "H15"
		)
		(pin "K36"
		)
		(pin "J24"
		)
		(pin "A54"
		)
		(pin "D32"
		)
		(pin "F62"
		)
		(pin "B54"
		)
		(pin "D33"
		)
		(pin "G14"
		)
		(pin "A22"
		)
		(pin "C14"
		)
		(pin "L3"
		)
		(pin "E2"
		)
		(pin "B11"
		)
		(pin "C23"
		)
		(pin "A12"
		)
		(pin "G15"
		)
		(pin "C15"
		)
		(pin "A59"
		)
		(pin "J15"
		)
		(pin "J57"
		)
		(pin "C7"
		)
		(pin "J14"
		)
		(pin "G59"
		)
		(pin "G39"
		)
		(pin "E54"
		)
		(pin "A37"
		)
		(pin "L41"
		)
		(pin "A14"
		)
		(pin "A15"
		)
		(pin "L51"
		)
		(pin "K47"
		)
		(pin "L46"
		)
		(pin "G4"
		)
		(pin "B15"
		)
		(pin "C34"
		)
		(pin "K46"
		)
		(pin "H37"
		)
		(pin "J48"
		)
		(pin "J47"
		)
		(pin "B9"
		)
		(pin "F49"
		)
		(pin "C22"
		)
		(pin "J39"
		)
		(pin "J13"
		)
		(pin "G50"
		)
		(pin "L6"
		)
		(pin "G51"
		)
		(pin "L8"
		)
		(pin "H9"
		)
		(pin "B56"
		)
		(pin "L53"
		)
		(pin "C12"
		)
		(pin "E59"
		)
		(pin "K24"
		)
		(pin "E52"
		)
		(pin "A27"
		)
		(pin "A31"
		)
		(pin "E21"
		)
		(pin "K17"
		)
		(pin "H49"
		)
		(pin "E22"
		)
		(pin "H21"
		)
		(pin "J63"
		)
		(pin "K28"
		)
		(pin "B28"
		)
		(pin "E65"
		)
		(pin "G52"
		)
		(pin "D44"
		)
		(pin "D47"
		)
		(pin "B4"
		)
		(pin "F2"
		)
		(pin "L35"
		)
		(pin "C52"
		)
		(pin "L42"
		)
		(pin "E32"
		)
		(pin "E37"
		)
		(pin "E33"
		)
		(pin "E43"
		)
		(pin "E15"
		)
		(pin "G30"
		)
		(pin "D41"
		)
		(pin "J31"
		)
		(pin "E9"
		)
		(pin "F14"
		)
		(pin "L5"
		)
		(pin "E3"
		)
		(pin "L34"
		)
		(pin "C25"
		)
		(pin "J4"
		)
		(pin "K42"
		)
		(pin "G63"
		)
		(pin "A16"
		)
		(pin "L30"
		)
		(pin "E1"
		)
		(pin "A36"
		)
		(pin "L20"
		)
		(pin "J2"
		)
		(pin "K45"
		)
		(pin "A3"
		)
		(pin "L23"
		)
		(pin "A33"
		)
		(pin "A17"
		)
		(pin "H41"
		)
		(pin "C46"
		)
		(pin "L31"
		)
		(pin "H44"
		)
		(pin "F64"
		)
		(pin "A28"
		)
		(pin "C21"
		)
		(pin "F1"
		)
		(pin "A20"
		)
		(pin "B53"
		)
		(pin "A29"
		)
		(pin "E49"
		)
		(pin "G27"
		)
		(pin "E14"
		)
		(pin "H4"
		)
		(pin "H13"
		)
		(pin "F32"
		)
		(pin "F13"
		)
		(pin "E36"
		)
		(pin "D39"
		)
		(pin "H48"
		)
		(pin "K43"
		)
		(pin "F40"
		)
		(pin "G57"
		)
		(pin "C4"
		)
		(pin "K53"
		)
		(pin "D40"
		)
		(pin "H46"
		)
		(pin "H10"
		)
		(pin "C56"
		)
		(pin "L21"
		)
		(pin "G6"
		)
		(pin "H28"
		)
		(pin "K13"
		)
		(pin "L47"
		)
		(pin "C48"
		)
		(pin "D10"
		)
		(pin "D43"
		)
		(pin "A44"
		)
		(pin "D46"
		)
		(pin "C45"
		)
		(pin "J9"
		)
		(pin "C50"
		)
		(pin "L16"
		)
		(pin "B46"
		)
		(pin "E47"
		)
		(pin "H36"
		)
		(pin "B45"
		)
		(pin "C44"
		)
		(pin "L18"
		)
		(pin "D42"
		)
		(pin "A8"
		)
		(pin "C38"
		)
		(pin "E48"
		)
		(pin "K49"
		)
		(pin "L50"
		)
		(pin "K54"
		)
		(pin "J29"
		)
		(pin "K48"
		)
		(pin "C61"
		)
		(pin "D21"
		)
		(pin "K5"
		)
		(pin "C51"
		)
		(pin "H53"
		)
		(pin "J7"
		)
		(pin "A50"
		)
		(pin "H56"
		)
		(pin "A51"
		)
		(pin "H47"
		)
		(pin "H18"
		)
		(pin "G47"
		)
		(pin "D6"
		)
		(pin "B51"
		)
		(pin "G5"
		)
		(pin "B52"
		)
		(pin "H22"
		)
		(pin "L14"
		)
		(pin "D52"
		)
		(pin "E31"
		)
		(pin "J53"
		)
		(pin "B61"
		)
		(pin "G20"
		)
		(pin "B60"
		)
		(pin "L29"
		)
		(pin "F31"
		)
		(pin "G60"
		)
		(pin "F60"
		)
		(pin "D51"
		)
		(pin "F56"
		)
		(pin "G38"
		)
		(pin "J50"
		)
		(pin "L45"
		)
		(pin "J43"
		)
		(pin "F8"
		)
		(pin "J34"
		)
		(pin "E51"
		)
		(pin "A43"
		)
		(pin "F36"
		)
		(pin "B30"
		)
		(pin "B32"
		)
		(pin "L44"
		)
		(pin "K62"
		)
		(pin "D2"
		)
		(pin "L57"
		)
		(pin "E45"
		)
		(pin "H55"
		)
		(pin "A47"
		)
		(pin "H1"
		)
		(pin "C29"
		)
		(pin "B6"
		)
		(pin "B20"
		)
		(pin "C33"
		)
		(pin "J55"
		)
		(pin "C64"
		)
		(pin "F47"
		)
		(pin "A55"
		)
		(pin "D60"
		)
		(pin "J52"
		)
		(pin "F51"
		)
		(pin "H5"
		)
		(pin "C28"
		)
		(pin "F7"
		)
		(pin "A48"
		)
		(pin "H59"
		)
		(pin "K6"
		)
		(pin "D36"
		)
		(pin "F6"
		)
		(pin "F52"
		)
		(pin "J49"
		)
		(pin "J19"
		)
		(pin "C5"
		)
		(pin "G56"
		)
		(pin "H17"
		)
		(pin "E58"
		)
		(pin "E27"
		)
		(pin "F38"
		)
		(pin "H6"
		)
		(pin "G21"
		)
		(pin "D26"
		)
		(pin "J11"
		)
		(pin "B16"
		)
		(pin "B59"
		)
		(pin "A5"
		)
		(pin "K58"
		)
		(pin "L48"
		)
		(pin "A58"
		)
		(pin "F61"
		)
		(pin "K15"
		)
		(pin "G23"
		)
		(pin "E4"
		)
		(pin "H31"
		)
		(pin "K10"
		)
		(pin "D65"
		)
		(pin "G34"
		)
		(pin "L38"
		)
		(pin "K33"
		)
		(pin "C43"
		)
		(pin "F18"
		)
		(pin "E35"
		)
		(pin "D48"
		)
		(pin "G18"
		)
		(pin "K9"
		)
		(pin "C53"
		)
		(pin "E6"
		)
		(pin "C55"
		)
		(pin "J8"
		)
		(pin "D35"
		)
		(pin "F48"
		)
		(pin "E44"
		)
		(pin "B55"
		)
		(pin "E34"
		)
		(pin "G11"
		)
		(pin "G61"
		)
		(pin "K51"
		)
		(pin "K20"
		)
		(pin "A49"
		)
		(pin "H23"
		)
		(pin "C62"
		)
		(pin "B24"
		)
		(pin "G2"
		)
		(pin "B14"
		)
		(pin "G22"
		)
		(pin "A60"
		)
		(pin "K27"
		)
		(pin "H54"
		)
		(pin "B7"
		)
		(pin "A61"
		)
		(pin "D56"
		)
		(pin "G32"
		)
		(pin "B26"
		)
		(pin "B44"
		)
		(pin "H38"
		)
		(pin "C49"
		)
		(pin "D15"
		)
		(pin "B49"
		)
		(pin "B17"
		)
		(pin "F35"
		)
		(pin "B39"
		)
		(pin "F5"
		)
		(pin "J3"
		)
		(pin "J46"
		)
		(pin "J28"
		)
		(pin "J36"
		)
		(pin "J25"
		)
		(pin "J32"
		)
		(pin "L22"
		)
		(pin "K22"
		)
		(pin "J20"
		)
		(pin "C32"
		)
		(pin "F10"
		)
		(pin "G16"
		)
		(pin "F55"
		)
		(pin "K40"
		)
		(pin "H20"
		)
		(pin "K32"
		)
		(pin "G3"
		)
		(pin "A32"
		)
		(pin "J10"
		)
		(pin "C13"
		)
		(pin "L55"
		)
		(pin "G46"
		)
		(pin "G35"
		)
		(pin "L26"
		)
		(pin "E60"
		)
		(pin "J23"
		)
		(pin "J22"
		)
		(pin "A21"
		)
		(pin "L39"
		)
		(pin "C36"
		)
		(pin "L36"
		)
		(pin "G17"
		)
		(pin "J58"
		)
		(pin "K52"
		)
		(pin "B25"
		)
		(pin "E11"
		)
		(pin "B36"
		)
		(pin "A52"
		)
		(pin "B35"
		)
		(pin "D3"
		)
		(pin "K21"
		)
		(pin "E26"
		)
		(pin "F23"
		)
		(pin "F26"
		)
		(pin "G9"
		)
		(pin "D61"
		)
		(pin "C37"
		)
		(pin "K23"
		)
		(pin "G28"
		)
		(pin "H34"
		)
		(pin "D30"
		)
		(pin "H50"
		)
		(pin "G49"
		)
		(pin "B47"
		)
		(pin "B31"
		)
		(pin "A18"
		)
		(pin "J17"
		)
		(pin "C8"
		)
		(pin "C26"
		)
		(pin "G29"
		)
		(pin "E53"
		)
		(pin "G8"
		)
		(pin "K34"
		)
		(pin "K31"
		)
		(pin "G31"
		)
		(pin "K59"
		)
		(pin "L61"
		)
		(pin "C9"
		)
		(pin "D14"
		)
		(pin "K39"
		)
		(pin "C60"
		)
		(pin "F17"
		)
		(pin "B10"
		)
		(pin "L33"
		)
		(pin "H11"
		)
		(pin "L13"
		)
		(pin "D31"
		)
		(pin "F33"
		)
		(pin "A39"
		)
		(pin "A6"
		)
		(pin "C57"
		)
		(pin "H8"
		)
		(pin "G24"
		)
		(pin "B19"
		)
		(pin "F53"
		)
		(pin "K38"
		)
		(pin "A23"
		)
		(pin "C59"
		)
		(pin "J56"
		)
		(pin "D54"
		)
		(pin "F4"
		)
		(pin "A4"
		)
		(pin "F15"
		)
		(pin "G55"
		)
		(pin "E55"
		)
		(pin "J45"
		)
		(pin "D58"
		)
		(pin "J44"
		)
		(pin "K41"
		)
		(pin "A11"
		)
		(pin "G62"
		)
		(pin "J6"
		)
		(pin "H2"
		)
		(pin "L7"
		)
		(pin "C35"
		)
		(pin "L4"
		)
		(pin "E10"
		)
		(pin "A7"
		)
		(pin "L28"
		)
		(pin "K3"
		)
		(pin "J1"
		)
		(pin "K61"
		)
		(pin "G37"
		)
		(pin "L58"
		)
		(pin "A53"
		)
		(pin "L40"
		)
		(pin "F22"
		)
		(pin "K18"
		)
		(pin "D38"
		)
		(pin "K11"
		)
		(pin "H58"
		)
		(pin "A62"
		)
		(pin "K35"
		)
		(pin "D64"
		)
		(pin "G44"
		)
		(pin "H52"
		)
		(pin "H14"
		)
		(pin "K44"
		)
		(pin "F30"
		)
		(pin "D11"
		)
		(pin "C39"
		)
		(pin "K8"
		)
		(pin "F29"
		)
		(pin "F58"
		)
		(pin "B8"
		)
		(pin "B57"
		)
		(pin "B23"
		)
		(pin "G10"
		)
		(pin "K55"
		)
		(pin "G25"
		)
		(pin "L37"
		)
		(pin "H27"
		)
		(pin "H3"
		)
		(pin "F54"
		)
		(pin "K19"
		)
		(pin "G45"
		)
		(pin "L11"
		)
		(pin "J16"
		)
		(pin "K60"
		)
		(pin "B40"
		)
		(pin "J62"
		)
		(pin "K63"
		)
		(pin "H57"
		)
		(pin "L19"
		)
		(pin "L17"
		)
		(pin "C63"
		)
		(pin "E8"
		)
		(pin "D25"
		)
		(pin "C1"
		)
		(pin "C2"
		)
		(pin "B3"
		)
		(pin "B63"
		)
		(pin "C65"
		)
		(pin "K26"
		)
		(pin "A26"
		)
		(pin "G43"
		)
		(pin "H60"
		)
		(pin "F24"
		)
		(pin "H24"
		)
		(pin "J27"
		)
		(pin "C17"
		)
		(pin "F11"
		)
		(pin "F19"
		)
		(pin "J61"
		)
		(pin "K14"
		)
		(pin "K57"
		)
		(pin "L32"
		)
		(pin "B62"
		)
		(pin "D22"
		)
		(pin "D34"
		)
		(pin "L63"
		)
		(pin "B41"
		)
		(pin "K30"
		)
		(pin "B37"
		)
		(pin "K4"
		)
		(instances
			(project ""
				(path ""
					(reference "J1")
					(unit 3)
				)
			)
		)
	)
	(symbol
		(lib_id "antmicroResistors0402:R_100k_0402")
		(at 213.36 265.43 0)
		(unit 1)
		(exclude_from_sim no)
		(in_bom yes)
		(on_board yes)
		(dnp no)
		(property "Reference" "R11"
			(at 211.836 264.16 0)
			(effects
				(font
					(size 1.27 1.27)
					(thickness 0.15)
				)
			)
		)
		(property "Value" "R_100k_0402"
			(at 233.68 278.13 0)
			(effects
				(font
					(size 1.27 1.27)
					(thickness 0.15)
				)
				(justify left bottom)
				(hide yes)
			)
		)
		(property "Footprint" "antmicro-footprints:R_0402_1005Metric"
			(at 233.68 280.67 0)
			(effects
				(font
					(size 1.27 1.27)
					(thickness 0.15)
				)
				(justify left bottom)
				(hide yes)
			)
		)
		(property "Datasheet" "https://www.bourns.com/docs/product-datasheets/cr.pdf"
			(at 233.68 283.21 0)
			(effects
				(font
					(size 1.27 1.27)
					(thickness 0.15)
				)
				(justify left bottom)
				(hide yes)
			)
		)
		(property "Description" "SMD Chip Resistor, 100 kohm, ± 1%, 62.5 mW, 0402 [1005 Metric], Thick Film, General Purpose"
			(at 213.36 265.43 0)
			(effects
				(font
					(size 1.27 1.27)
				)
				(hide yes)
			)
		)
		(property "MPN" "CR0402-FX-1003GLF"
			(at 233.68 285.75 0)
			(effects
				(font
					(size 1.27 1.27)
					(thickness 0.15)
				)
				(justify left bottom)
				(hide yes)
			)
		)
		(property "Manufacturer" "Bourns"
			(at 233.68 288.29 0)
			(effects
				(font
					(size 1.27 1.27)
					(thickness 0.15)
				)
				(justify left bottom)
				(hide yes)
			)
		)
		(property "License" "Apache-2.0"
			(at 233.68 290.83 0)
			(effects
				(font
					(size 1.27 1.27)
					(thickness 0.15)
				)
				(justify left bottom)
				(hide yes)
			)
		)
		(property "Author" "Antmicro"
			(at 233.68 293.37 0)
			(effects
				(font
					(size 1.27 1.27)
					(thickness 0.15)
				)
				(justify left bottom)
				(hide yes)
			)
		)
		(property "Val" "100k"
			(at 220.472 264.16 0)
			(effects
				(font
					(size 1.27 1.27)
					(thickness 0.15)
				)
			)
		)
		(property "Tolerance" "1%"
			(at 233.68 275.59 0)
			(effects
				(font
					(size 1.27 1.27)
				)
				(justify left bottom)
				(hide yes)
			)
		)
		(pin "1"
		)
		(pin "2"
		)
		(instances
			(project "jetson-agx-thor-baseboard"
				(path ""
					(reference "R11")
					(unit 1)
				)
			)
		)
	)
	(symbol
		(lib_id "antmicroCapacitors0402:C_100n_0402")
		(at 279.4 77.47 0)
		(mirror x)
		(unit 1)
		(exclude_from_sim no)
		(in_bom yes)
		(on_board yes)
		(dnp no)
		(property "Reference" "C326"
			(at 288.29 76.2 0)
			(effects
				(font
					(size 1.27 1.27)
				)
				(justify right)
			)
		)
		(property "Value" "C_100n_0402"
			(at 299.72 67.31 0)
			(effects
				(font
					(size 1.27 1.27)
					(thickness 0.15)
				)
				(justify left bottom)
				(hide yes)
			)
		)
		(property "Footprint" "antmicro-footprints:C_0402_1005Metric"
			(at 299.72 64.77 0)
			(effects
				(font
					(size 1.27 1.27)
					(thickness 0.15)
				)
				(justify left bottom)
				(hide yes)
			)
		)
		(property "Datasheet" "https://www.murata.com/products/productdetail?partno=GRM155R61H104KE14%23"
			(at 299.72 62.23 0)
			(effects
				(font
					(size 1.27 1.27)
					(thickness 0.15)
				)
				(justify left bottom)
				(hide yes)
			)
		)
		(property "Description" "SMD Multilayer Ceramic Capacitor, 0.1 µF, 50 V, 0402 [1005 Metric], ± 10%, X5R, GRM Series"
			(at 279.4 77.47 0)
			(effects
				(font
					(size 1.27 1.27)
				)
				(hide yes)
			)
		)
		(property "Manufacturer" "Murata"
			(at 299.72 57.15 0)
			(effects
				(font
					(size 1.27 1.27)
					(thickness 0.15)
				)
				(justify left bottom)
				(hide yes)
			)
		)
		(property "MPN" "GRM155R61H104KE14D"
			(at 299.72 59.69 0)
			(effects
				(font
					(size 1.27 1.27)
					(thickness 0.15)
				)
				(justify left bottom)
				(hide yes)
			)
		)
		(property "Val" "100n"
			(at 280.924 76.454 0)
			(effects
				(font
					(size 1.27 1.27)
					(thickness 0.15)
				)
				(justify right)
			)
		)
		(property "License" "Apache-2.0"
			(at 299.72 54.61 0)
			(effects
				(font
					(size 1.27 1.27)
					(thickness 0.15)
				)
				(justify left bottom)
				(hide yes)
			)
		)
		(property "Author" "Antmicro"
			(at 299.72 52.07 0)
			(effects
				(font
					(size 1.27 1.27)
					(thickness 0.15)
				)
				(justify left bottom)
				(hide yes)
			)
		)
		(property "Voltage" "50V"
			(at 299.72 49.53 0)
			(effects
				(font
					(size 1.27 1.27)
				)
				(justify left bottom)
				(hide yes)
			)
		)
		(property "Dielectric" "X5R"
			(at 299.72 46.99 0)
			(effects
				(font
					(size 1.27 1.27)
				)
				(justify left bottom)
				(hide yes)
			)
		)
		(pin "1"
		)
		(pin "2"
		)
		(instances
			(project "jetson-agx-thor-baseboard"
				(path ""
					(reference "C326")
					(unit 1)
				)
			)
		)
	)
	(symbol
		(lib_id "antmicroCapacitors0402:C_100n_0402")
		(at 365.76 57.15 0)
		(mirror x)
		(unit 1)
		(exclude_from_sim no)
		(in_bom yes)
		(on_board yes)
		(dnp no)
		(property "Reference" "C322"
			(at 374.65 55.88 0)
			(effects
				(font
					(size 1.27 1.27)
				)
				(justify right)
			)
		)
		(property "Value" "C_100n_0402"
			(at 386.08 46.99 0)
			(effects
				(font
					(size 1.27 1.27)
					(thickness 0.15)
				)
				(justify left bottom)
				(hide yes)
			)
		)
		(property "Footprint" "antmicro-footprints:C_0402_1005Metric"
			(at 386.08 44.45 0)
			(effects
				(font
					(size 1.27 1.27)
					(thickness 0.15)
				)
				(justify left bottom)
				(hide yes)
			)
		)
		(property "Datasheet" "https://www.murata.com/products/productdetail?partno=GRM155R61H104KE14%23"
			(at 386.08 41.91 0)
			(effects
				(font
					(size 1.27 1.27)
					(thickness 0.15)
				)
				(justify left bottom)
				(hide yes)
			)
		)
		(property "Description" "SMD Multilayer Ceramic Capacitor, 0.1 µF, 50 V, 0402 [1005 Metric], ± 10%, X5R, GRM Series"
			(at 365.76 57.15 0)
			(effects
				(font
					(size 1.27 1.27)
				)
				(hide yes)
			)
		)
		(property "Manufacturer" "Murata"
			(at 386.08 36.83 0)
			(effects
				(font
					(size 1.27 1.27)
					(thickness 0.15)
				)
				(justify left bottom)
				(hide yes)
			)
		)
		(property "MPN" "GRM155R61H104KE14D"
			(at 386.08 39.37 0)
			(effects
				(font
					(size 1.27 1.27)
					(thickness 0.15)
				)
				(justify left bottom)
				(hide yes)
			)
		)
		(property "Val" "100n"
			(at 367.284 56.134 0)
			(effects
				(font
					(size 1.27 1.27)
					(thickness 0.15)
				)
				(justify right)
			)
		)
		(property "License" "Apache-2.0"
			(at 386.08 34.29 0)
			(effects
				(font
					(size 1.27 1.27)
					(thickness 0.15)
				)
				(justify left bottom)
				(hide yes)
			)
		)
		(property "Author" "Antmicro"
			(at 386.08 31.75 0)
			(effects
				(font
					(size 1.27 1.27)
					(thickness 0.15)
				)
				(justify left bottom)
				(hide yes)
			)
		)
		(property "Voltage" "50V"
			(at 386.08 29.21 0)
			(effects
				(font
					(size 1.27 1.27)
				)
				(justify left bottom)
				(hide yes)
			)
		)
		(property "Dielectric" "X5R"
			(at 386.08 26.67 0)
			(effects
				(font
					(size 1.27 1.27)
				)
				(justify left bottom)
				(hide yes)
			)
		)
		(pin "1"
		)
		(pin "2"
		)
		(instances
			(project "jetson-agx-thor-baseboard"
				(path ""
					(reference "C322")
					(unit 1)
				)
			)
		)
	)
	(symbol
		(lib_id "antmicroCapacitors0402:C_100n_0402")
		(at 287.02 80.01 0)
		(mirror x)
		(unit 1)
		(exclude_from_sim no)
		(in_bom yes)
		(on_board yes)
		(dnp no)
		(property "Reference" "C330"
			(at 295.656 78.74 0)
			(effects
				(font
					(size 1.27 1.27)
				)
				(justify right)
			)
		)
		(property "Value" "C_100n_0402"
			(at 307.34 69.85 0)
			(effects
				(font
					(size 1.27 1.27)
					(thickness 0.15)
				)
				(justify left bottom)
				(hide yes)
			)
		)
		(property "Footprint" "antmicro-footprints:C_0402_1005Metric"
			(at 307.34 67.31 0)
			(effects
				(font
					(size 1.27 1.27)
					(thickness 0.15)
				)
				(justify left bottom)
				(hide yes)
			)
		)
		(property "Datasheet" "https://www.murata.com/products/productdetail?partno=GRM155R61H104KE14%23"
			(at 307.34 64.77 0)
			(effects
				(font
					(size 1.27 1.27)
					(thickness 0.15)
				)
				(justify left bottom)
				(hide yes)
			)
		)
		(property "Description" "SMD Multilayer Ceramic Capacitor, 0.1 µF, 50 V, 0402 [1005 Metric], ± 10%, X5R, GRM Series"
			(at 287.02 80.01 0)
			(effects
				(font
					(size 1.27 1.27)
				)
				(hide yes)
			)
		)
		(property "Manufacturer" "Murata"
			(at 307.34 59.69 0)
			(effects
				(font
					(size 1.27 1.27)
					(thickness 0.15)
				)
				(justify left bottom)
				(hide yes)
			)
		)
		(property "MPN" "GRM155R61H104KE14D"
			(at 307.34 62.23 0)
			(effects
				(font
					(size 1.27 1.27)
					(thickness 0.15)
				)
				(justify left bottom)
				(hide yes)
			)
		)
		(property "Val" "100n"
			(at 288.544 78.994 0)
			(effects
				(font
					(size 1.27 1.27)
					(thickness 0.15)
				)
				(justify right)
			)
		)
		(property "License" "Apache-2.0"
			(at 307.34 57.15 0)
			(effects
				(font
					(size 1.27 1.27)
					(thickness 0.15)
				)
				(justify left bottom)
				(hide yes)
			)
		)
		(property "Author" "Antmicro"
			(at 307.34 54.61 0)
			(effects
				(font
					(size 1.27 1.27)
					(thickness 0.15)
				)
				(justify left bottom)
				(hide yes)
			)
		)
		(property "Voltage" "50V"
			(at 307.34 52.07 0)
			(effects
				(font
					(size 1.27 1.27)
				)
				(justify left bottom)
				(hide yes)
			)
		)
		(property "Dielectric" "X5R"
			(at 307.34 49.53 0)
			(effects
				(font
					(size 1.27 1.27)
				)
				(justify left bottom)
				(hide yes)
			)
		)
		(pin "1"
		)
		(pin "2"
		)
		(instances
			(project "jetson-agx-thor-baseboard"
				(path ""
					(reference "C330")
					(unit 1)
				)
			)
		)
	)
	(symbol
		(lib_id "antmicroCapacitors0402:C_100n_0402")
		(at 287.02 135.89 0)
		(mirror x)
		(unit 1)
		(exclude_from_sim no)
		(in_bom yes)
		(on_board yes)
		(dnp no)
		(property "Reference" "C351"
			(at 295.656 134.62 0)
			(effects
				(font
					(size 1.27 1.27)
				)
				(justify right)
			)
		)
		(property "Value" "C_100n_0402"
			(at 307.34 125.73 0)
			(effects
				(font
					(size 1.27 1.27)
					(thickness 0.15)
				)
				(justify left bottom)
				(hide yes)
			)
		)
		(property "Footprint" "antmicro-footprints:C_0402_1005Metric"
			(at 307.34 123.19 0)
			(effects
				(font
					(size 1.27 1.27)
					(thickness 0.15)
				)
				(justify left bottom)
				(hide yes)
			)
		)
		(property "Datasheet" "https://www.murata.com/products/productdetail?partno=GRM155R61H104KE14%23"
			(at 307.34 120.65 0)
			(effects
				(font
					(size 1.27 1.27)
					(thickness 0.15)
				)
				(justify left bottom)
				(hide yes)
			)
		)
		(property "Description" "SMD Multilayer Ceramic Capacitor, 0.1 µF, 50 V, 0402 [1005 Metric], ± 10%, X5R, GRM Series"
			(at 287.02 135.89 0)
			(effects
				(font
					(size 1.27 1.27)
				)
				(hide yes)
			)
		)
		(property "Manufacturer" "Murata"
			(at 307.34 115.57 0)
			(effects
				(font
					(size 1.27 1.27)
					(thickness 0.15)
				)
				(justify left bottom)
				(hide yes)
			)
		)
		(property "MPN" "GRM155R61H104KE14D"
			(at 307.34 118.11 0)
			(effects
				(font
					(size 1.27 1.27)
					(thickness 0.15)
				)
				(justify left bottom)
				(hide yes)
			)
		)
		(property "Val" "100n"
			(at 288.544 134.874 0)
			(effects
				(font
					(size 1.27 1.27)
					(thickness 0.15)
				)
				(justify right)
			)
		)
		(property "License" "Apache-2.0"
			(at 307.34 113.03 0)
			(effects
				(font
					(size 1.27 1.27)
					(thickness 0.15)
				)
				(justify left bottom)
				(hide yes)
			)
		)
		(property "Author" "Antmicro"
			(at 307.34 110.49 0)
			(effects
				(font
					(size 1.27 1.27)
					(thickness 0.15)
				)
				(justify left bottom)
				(hide yes)
			)
		)
		(property "Voltage" "50V"
			(at 307.34 107.95 0)
			(effects
				(font
					(size 1.27 1.27)
				)
				(justify left bottom)
				(hide yes)
			)
		)
		(property "Dielectric" "X5R"
			(at 307.34 105.41 0)
			(effects
				(font
					(size 1.27 1.27)
				)
				(justify left bottom)
				(hide yes)
			)
		)
		(pin "1"
		)
		(pin "2"
		)
		(instances
			(project "jetson-agx-thor-baseboard"
				(path ""
					(reference "C351")
					(unit 1)
				)
			)
		)
	)
	(symbol
		(lib_id "antmicroCapacitors0402:C_100n_0402")
		(at 287.02 44.45 0)
		(mirror x)
		(unit 1)
		(exclude_from_sim no)
		(in_bom yes)
		(on_board yes)
		(dnp no)
		(property "Reference" "C315"
			(at 295.656 43.18 0)
			(effects
				(font
					(size 1.27 1.27)
				)
				(justify right)
			)
		)
		(property "Value" "C_100n_0402"
			(at 307.34 34.29 0)
			(effects
				(font
					(size 1.27 1.27)
					(thickness 0.15)
				)
				(justify left bottom)
				(hide yes)
			)
		)
		(property "Footprint" "antmicro-footprints:C_0402_1005Metric"
			(at 307.34 31.75 0)
			(effects
				(font
					(size 1.27 1.27)
					(thickness 0.15)
				)
				(justify left bottom)
				(hide yes)
			)
		)
		(property "Datasheet" "https://www.murata.com/products/productdetail?partno=GRM155R61H104KE14%23"
			(at 307.34 29.21 0)
			(effects
				(font
					(size 1.27 1.27)
					(thickness 0.15)
				)
				(justify left bottom)
				(hide yes)
			)
		)
		(property "Description" "SMD Multilayer Ceramic Capacitor, 0.1 µF, 50 V, 0402 [1005 Metric], ± 10%, X5R, GRM Series"
			(at 287.02 44.45 0)
			(effects
				(font
					(size 1.27 1.27)
				)
				(hide yes)
			)
		)
		(property "Manufacturer" "Murata"
			(at 307.34 24.13 0)
			(effects
				(font
					(size 1.27 1.27)
					(thickness 0.15)
				)
				(justify left bottom)
				(hide yes)
			)
		)
		(property "MPN" "GRM155R61H104KE14D"
			(at 307.34 26.67 0)
			(effects
				(font
					(size 1.27 1.27)
					(thickness 0.15)
				)
				(justify left bottom)
				(hide yes)
			)
		)
		(property "Val" "100n"
			(at 288.544 43.434 0)
			(effects
				(font
					(size 1.27 1.27)
					(thickness 0.15)
				)
				(justify right)
			)
		)
		(property "License" "Apache-2.0"
			(at 307.34 21.59 0)
			(effects
				(font
					(size 1.27 1.27)
					(thickness 0.15)
				)
				(justify left bottom)
				(hide yes)
			)
		)
		(property "Author" "Antmicro"
			(at 307.34 19.05 0)
			(effects
				(font
					(size 1.27 1.27)
					(thickness 0.15)
				)
				(justify left bottom)
				(hide yes)
			)
		)
		(property "Voltage" "50V"
			(at 307.34 16.51 0)
			(effects
				(font
					(size 1.27 1.27)
				)
				(justify left bottom)
				(hide yes)
			)
		)
		(property "Dielectric" "X5R"
			(at 307.34 13.97 0)
			(effects
				(font
					(size 1.27 1.27)
				)
				(justify left bottom)
				(hide yes)
			)
		)
		(pin "1"
		)
		(pin "2"
		)
		(instances
			(project "jetson-agx-thor-baseboard"
				(path ""
					(reference "C315")
					(unit 1)
				)
			)
		)
	)
	(symbol
		(lib_id "antmicroResistors0402:R_0R_0402")
		(at 46.99 82.55 0)
		(unit 1)
		(exclude_from_sim no)
		(in_bom yes)
		(on_board yes)
		(dnp no)
		(property "Reference" "R202"
			(at 43.942 81.28 0)
			(effects
				(font
					(size 1.27 1.27)
					(thickness 0.15)
				)
			)
		)
		(property "Value" "R_0R_0402"
			(at 67.31 95.25 0)
			(effects
				(font
					(size 1.27 1.27)
					(thickness 0.15)
				)
				(justify left bottom)
				(hide yes)
			)
		)
		(property "Footprint" "antmicro-footprints:R_0402_1005Metric"
			(at 67.31 97.79 0)
			(effects
				(font
					(size 1.27 1.27)
					(thickness 0.15)
				)
				(justify left bottom)
				(hide yes)
			)
		)
		(property "Datasheet" "https://industrial.panasonic.com/cdbs/www-data/pdf/RDA0000/AOA0000C301.pdf"
			(at 67.31 100.33 0)
			(effects
				(font
					(size 1.27 1.27)
					(thickness 0.15)
				)
				(justify left bottom)
				(hide yes)
			)
		)
		(property "Description" "SMD Chip Resistor, Jumper, 0 ohm, 100 mW, 0402 [1005 Metric], Thick Film, General Purpose"
			(at 46.99 82.55 0)
			(effects
				(font
					(size 1.27 1.27)
				)
				(hide yes)
			)
		)
		(property "MPN" "ERJ2GE0R00X"
			(at 67.31 102.87 0)
			(effects
				(font
					(size 1.27 1.27)
					(thickness 0.15)
				)
				(justify left bottom)
				(hide yes)
			)
		)
		(property "Manufacturer" "Panasonic"
			(at 67.31 105.41 0)
			(effects
				(font
					(size 1.27 1.27)
					(thickness 0.15)
				)
				(justify left bottom)
				(hide yes)
			)
		)
		(property "License" "Apache-2.0"
			(at 67.31 107.95 0)
			(effects
				(font
					(size 1.27 1.27)
					(thickness 0.15)
				)
				(justify left bottom)
				(hide yes)
			)
		)
		(property "Author" "Antmicro"
			(at 67.31 110.49 0)
			(effects
				(font
					(size 1.27 1.27)
					(thickness 0.15)
				)
				(justify left bottom)
				(hide yes)
			)
		)
		(property "Val" "0R"
			(at 53.34 81.28 0)
			(effects
				(font
					(size 1.27 1.27)
					(thickness 0.15)
				)
			)
		)
		(property "Tolerance" "~"
			(at 67.31 92.71 0)
			(effects
				(font
					(size 1.27 1.27)
				)
				(justify left bottom)
				(hide yes)
			)
		)
		(property "Current" "1A"
			(at 67.31 113.03 0)
			(effects
				(font
					(size 1.27 1.27)
					(thickness 0.15)
				)
				(justify left bottom)
				(hide yes)
			)
		)
		(pin "1"
		)
		(pin "2"
		)
		(instances
			(project "jetson-agx-thor-baseboard"
				(path ""
					(reference "R202")
					(unit 1)
				)
			)
		)
	)
	(symbol
		(lib_id "antmicropower:GND")
		(at 170.18 245.11 0)
		(mirror y)
		(unit 1)
		(exclude_from_sim no)
		(in_bom yes)
		(on_board yes)
		(dnp no)
		(property "Reference" "#PWR0496"
			(at 161.29 247.65 0)
			(effects
				(font
					(size 1.27 1.27)
					(thickness 0.15)
				)
				(justify left bottom)
				(hide yes)
			)
		)
		(property "Value" "GND"
			(at 170.18 248.92 0)
			(effects
				(font
					(size 1.27 1.27)
					(thickness 0.15)
				)
			)
		)
		(property "Footprint" ""
			(at 161.29 252.73 0)
			(effects
				(font
					(size 1.27 1.27)
					(thickness 0.15)
				)
				(justify left bottom)
				(hide yes)
			)
		)
		(property "Datasheet" ""
			(at 161.29 257.81 0)
			(effects
				(font
					(size 1.27 1.27)
					(thickness 0.15)
				)
				(justify left bottom)
				(hide yes)
			)
		)
		(property "Description" ""
			(at 170.18 245.11 0)
			(effects
				(font
					(size 1.27 1.27)
				)
				(hide yes)
			)
		)
		(property "Author" "Antmicro"
			(at 161.29 252.73 0)
			(effects
				(font
					(size 1.27 1.27)
					(thickness 0.15)
				)
				(justify left bottom)
				(hide yes)
			)
		)
		(property "License" "Apache-2.0"
			(at 161.29 255.27 0)
			(effects
				(font
					(size 1.27 1.27)
					(thickness 0.15)
				)
				(justify left bottom)
				(hide yes)
			)
		)
		(pin "1"
		)
		(instances
			(project "jetson-agx-thor-baseboard"
				(path ""
					(reference "#PWR0496")
					(unit 1)
				)
			)
		)
	)
	(symbol
		(lib_id "antmicroCapacitors0402:C_100n_0402")
		(at 115.57 240.03 90)
		(unit 1)
		(exclude_from_sim no)
		(in_bom no)
		(on_board yes)
		(dnp yes)
		(property "Reference" "C237"
			(at 118.11 236.2136 90)
			(effects
				(font
					(size 1.27 1.27)
					(thickness 0.15)
				)
				(justify right)
			)
		)
		(property "Value" "C_100n_0402"
			(at 138.43 224.79 0)
			(effects
				(font
					(size 1.27 1.27)
					(thickness 0.15)
				)
				(justify left bottom)
				(hide yes)
			)
		)
		(property "Footprint" "antmicro-footprints:C_0402_1005Metric"
			(at 140.97 224.79 0)
			(effects
				(font
					(size 1.27 1.27)
					(thickness 0.15)
				)
				(justify left bottom)
				(hide yes)
			)
		)
		(property "Datasheet" "https://www.murata.com/products/productdetail?partno=GRM155R61H104KE14%23"
			(at 143.51 224.79 0)
			(effects
				(font
					(size 1.27 1.27)
					(thickness 0.15)
				)
				(justify left bottom)
				(hide yes)
			)
		)
		(property "Description" "SMD Multilayer Ceramic Capacitor, 0.1 µF, 50 V, 0402 [1005 Metric], ± 10%, X5R, GRM Series"
			(at 115.57 240.03 0)
			(effects
				(font
					(size 1.27 1.27)
				)
				(hide yes)
			)
		)
		(property "MPN" "GRM155R61H104KE14D"
			(at 146.05 224.79 0)
			(effects
				(font
					(size 1.27 1.27)
					(thickness 0.15)
				)
				(justify left bottom)
				(hide yes)
			)
		)
		(property "Val" "100n"
			(at 118.11 238.7536 90)
			(effects
				(font
					(size 1.27 1.27)
					(thickness 0.15)
				)
				(justify right)
			)
		)
		(property "Voltage" "50V"
			(at 125.73 224.79 0)
			(effects
				(font
					(size 1.27 1.27)
					(thickness 0.15)
				)
				(justify left bottom)
				(hide yes)
			)
		)
		(property "Dielectric" "X5R"
			(at 128.27 224.79 0)
			(effects
				(font
					(size 1.27 1.27)
					(thickness 0.15)
				)
				(justify left bottom)
				(hide yes)
			)
		)
		(property "Manufacturer" "Murata"
			(at 130.81 224.79 0)
			(effects
				(font
					(size 1.27 1.27)
					(thickness 0.15)
				)
				(justify left bottom)
				(hide yes)
			)
		)
		(property "License" "Apache-2.0"
			(at 133.35 224.79 0)
			(effects
				(font
					(size 1.27 1.27)
					(thickness 0.15)
				)
				(justify left bottom)
				(hide yes)
			)
		)
		(property "Author" "Antmicro"
			(at 135.89 224.79 0)
			(effects
				(font
					(size 1.27 1.27)
					(thickness 0.15)
				)
				(justify left bottom)
				(hide yes)
			)
		)
		(pin "2"
		)
		(pin "1"
		)
		(instances
			(project "jetson-agx-thor-baseboard"
				(path ""
					(reference "C237")
					(unit 1)
				)
			)
		)
	)
	(symbol
		(lib_id "antmicroCapacitors0402:C_100n_0402")
		(at 279.4 133.35 0)
		(mirror x)
		(unit 1)
		(exclude_from_sim no)
		(in_bom yes)
		(on_board yes)
		(dnp no)
		(property "Reference" "C347"
			(at 288.29 132.08 0)
			(effects
				(font
					(size 1.27 1.27)
				)
				(justify right)
			)
		)
		(property "Value" "C_100n_0402"
			(at 299.72 123.19 0)
			(effects
				(font
					(size 1.27 1.27)
					(thickness 0.15)
				)
				(justify left bottom)
				(hide yes)
			)
		)
		(property "Footprint" "antmicro-footprints:C_0402_1005Metric"
			(at 299.72 120.65 0)
			(effects
				(font
					(size 1.27 1.27)
					(thickness 0.15)
				)
				(justify left bottom)
				(hide yes)
			)
		)
		(property "Datasheet" "https://www.murata.com/products/productdetail?partno=GRM155R61H104KE14%23"
			(at 299.72 118.11 0)
			(effects
				(font
					(size 1.27 1.27)
					(thickness 0.15)
				)
				(justify left bottom)
				(hide yes)
			)
		)
		(property "Description" "SMD Multilayer Ceramic Capacitor, 0.1 µF, 50 V, 0402 [1005 Metric], ± 10%, X5R, GRM Series"
			(at 279.4 133.35 0)
			(effects
				(font
					(size 1.27 1.27)
				)
				(hide yes)
			)
		)
		(property "Manufacturer" "Murata"
			(at 299.72 113.03 0)
			(effects
				(font
					(size 1.27 1.27)
					(thickness 0.15)
				)
				(justify left bottom)
				(hide yes)
			)
		)
		(property "MPN" "GRM155R61H104KE14D"
			(at 299.72 115.57 0)
			(effects
				(font
					(size 1.27 1.27)
					(thickness 0.15)
				)
				(justify left bottom)
				(hide yes)
			)
		)
		(property "Val" "100n"
			(at 280.924 132.334 0)
			(effects
				(font
					(size 1.27 1.27)
					(thickness 0.15)
				)
				(justify right)
			)
		)
		(property "License" "Apache-2.0"
			(at 299.72 110.49 0)
			(effects
				(font
					(size 1.27 1.27)
					(thickness 0.15)
				)
				(justify left bottom)
				(hide yes)
			)
		)
		(property "Author" "Antmicro"
			(at 299.72 107.95 0)
			(effects
				(font
					(size 1.27 1.27)
					(thickness 0.15)
				)
				(justify left bottom)
				(hide yes)
			)
		)
		(property "Voltage" "50V"
			(at 299.72 105.41 0)
			(effects
				(font
					(size 1.27 1.27)
				)
				(justify left bottom)
				(hide yes)
			)
		)
		(property "Dielectric" "X5R"
			(at 299.72 102.87 0)
			(effects
				(font
					(size 1.27 1.27)
				)
				(justify left bottom)
				(hide yes)
			)
		)
		(pin "1"
		)
		(pin "2"
		)
		(instances
			(project "jetson-agx-thor-baseboard"
				(path ""
					(reference "C347")
					(unit 1)
				)
			)
		)
	)
	(symbol
		(lib_id "antmicroCapacitors0402:C_100n_0402")
		(at 205.74 241.3 270)
		(mirror x)
		(unit 1)
		(exclude_from_sim no)
		(in_bom yes)
		(on_board yes)
		(dnp no)
		(property "Reference" "C199"
			(at 203.2 237.4836 90)
			(effects
				(font
					(size 1.27 1.27)
					(thickness 0.15)
				)
				(justify right)
			)
		)
		(property "Value" "C_100n_0402"
			(at 195.58 220.98 0)
			(effects
				(font
					(size 1.27 1.27)
					(thickness 0.15)
				)
				(justify left bottom)
				(hide yes)
			)
		)
		(property "Footprint" "antmicro-footprints:C_0402_1005Metric"
			(at 193.04 220.98 0)
			(effects
				(font
					(size 1.27 1.27)
					(thickness 0.15)
				)
				(justify left bottom)
				(hide yes)
			)
		)
		(property "Datasheet" "https://www.murata.com/products/productdetail?partno=GRM155R61H104KE14%23"
			(at 190.5 220.98 0)
			(effects
				(font
					(size 1.27 1.27)
					(thickness 0.15)
				)
				(justify left bottom)
				(hide yes)
			)
		)
		(property "Description" "SMD Multilayer Ceramic Capacitor, 0.1 µF, 50 V, 0402 [1005 Metric], ± 10%, X5R, GRM Series"
			(at 205.74 241.3 0)
			(effects
				(font
					(size 1.27 1.27)
				)
				(hide yes)
			)
		)
		(property "MPN" "GRM155R61H104KE14D"
			(at 187.96 220.98 0)
			(effects
				(font
					(size 1.27 1.27)
					(thickness 0.15)
				)
				(justify left bottom)
				(hide yes)
			)
		)
		(property "Manufacturer" "Murata"
			(at 185.42 220.98 0)
			(effects
				(font
					(size 1.27 1.27)
					(thickness 0.15)
				)
				(justify left bottom)
				(hide yes)
			)
		)
		(property "License" "Apache-2.0"
			(at 182.88 220.98 0)
			(effects
				(font
					(size 1.27 1.27)
					(thickness 0.15)
				)
				(justify left bottom)
				(hide yes)
			)
		)
		(property "Author" "Antmicro"
			(at 180.34 220.98 0)
			(effects
				(font
					(size 1.27 1.27)
					(thickness 0.15)
				)
				(justify left bottom)
				(hide yes)
			)
		)
		(property "Val" "100n"
			(at 203.2 240.0236 90)
			(effects
				(font
					(size 1.27 1.27)
					(thickness 0.15)
				)
				(justify right)
			)
		)
		(property "Voltage" "50V"
			(at 177.8 220.98 0)
			(effects
				(font
					(size 1.27 1.27)
				)
				(justify left bottom)
				(hide yes)
			)
		)
		(property "Dielectric" "X5R"
			(at 175.26 220.98 0)
			(effects
				(font
					(size 1.27 1.27)
				)
				(justify left bottom)
				(hide yes)
			)
		)
		(pin "1"
		)
		(pin "2"
		)
		(instances
			(project "jetson-agx-thor-baseboard"
				(path ""
					(reference "C199")
					(unit 1)
				)
			)
		)
	)
	(symbol
		(lib_id "antmicroResistors0402:R_49R9_0402")
		(at 274.32 273.05 90)
		(unit 1)
		(exclude_from_sim no)
		(in_bom yes)
		(on_board yes)
		(dnp no)
		(property "Reference" "R193"
			(at 275.59 269.24 90)
			(effects
				(font
					(size 1.27 1.27)
					(thickness 0.15)
				)
				(justify right)
			)
		)
		(property "Value" "R_49R9_0402"
			(at 287.02 252.73 0)
			(effects
				(font
					(size 1.27 1.27)
					(thickness 0.15)
				)
				(justify left bottom)
				(hide yes)
			)
		)
		(property "Footprint" "antmicro-footprints:R_0402_1005Metric"
			(at 289.56 252.73 0)
			(effects
				(font
					(size 1.27 1.27)
					(thickness 0.15)
				)
				(justify left bottom)
				(hide yes)
			)
		)
		(property "Datasheet" "https://www.bourns.com/docs/product-datasheets/cr.pdf"
			(at 292.1 252.73 0)
			(effects
				(font
					(size 1.27 1.27)
					(thickness 0.15)
				)
				(justify left bottom)
				(hide yes)
			)
		)
		(property "Description" "SMD Chip Resistor, 49.9 ohm, ± 1%, 62.5 mW, 0402 [1005 Metric], Thick Film, General Purpose"
			(at 274.32 273.05 0)
			(effects
				(font
					(size 1.27 1.27)
				)
				(hide yes)
			)
		)
		(property "MPN" "CR0402-FX-49R9GLF"
			(at 294.64 252.73 0)
			(effects
				(font
					(size 1.27 1.27)
					(thickness 0.15)
				)
				(justify left bottom)
				(hide yes)
			)
		)
		(property "Manufacturer" "Bourns"
			(at 297.18 252.73 0)
			(effects
				(font
					(size 1.27 1.27)
					(thickness 0.15)
				)
				(justify left bottom)
				(hide yes)
			)
		)
		(property "License" "Apache-2.0"
			(at 299.72 252.73 0)
			(effects
				(font
					(size 1.27 1.27)
					(thickness 0.15)
				)
				(justify left bottom)
				(hide yes)
			)
		)
		(property "Author" "Antmicro"
			(at 302.26 252.73 0)
			(effects
				(font
					(size 1.27 1.27)
					(thickness 0.15)
				)
				(justify left bottom)
				(hide yes)
			)
		)
		(property "Val" "49R9"
			(at 275.59 271.78 90)
			(effects
				(font
					(size 1.27 1.27)
					(thickness 0.15)
				)
				(justify right)
			)
		)
		(property "Tolerance" "1%"
			(at 284.48 252.73 0)
			(effects
				(font
					(size 1.27 1.27)
				)
				(justify left bottom)
				(hide yes)
			)
		)
		(pin "1"
		)
		(pin "2"
		)
		(instances
			(project "jetson-agx-thor-baseboard"
				(path ""
					(reference "R193")
					(unit 1)
				)
			)
		)
	)
	(symbol
		(lib_id "antmicropower:GND")
		(at 205.74 270.51 0)
		(mirror y)
		(unit 1)
		(exclude_from_sim no)
		(in_bom yes)
		(on_board yes)
		(dnp no)
		(property "Reference" "#PWR0348"
			(at 205.74 276.86 0)
			(effects
				(font
					(size 1.27 1.27)
				)
				(justify left bottom)
				(hide yes)
			)
		)
		(property "Value" "GND"
			(at 205.74 274.32 0)
			(effects
				(font
					(size 1.27 1.27)
				)
			)
		)
		(property "Footprint" ""
			(at 205.74 270.51 0)
			(effects
				(font
					(size 1.27 1.27)
				)
				(justify left bottom)
				(hide yes)
			)
		)
		(property "Datasheet" ""
			(at 205.74 270.51 0)
			(effects
				(font
					(size 1.27 1.27)
				)
				(justify left bottom)
				(hide yes)
			)
		)
		(property "Description" ""
			(at 205.74 270.51 0)
			(effects
				(font
					(size 1.27 1.27)
				)
				(hide yes)
			)
		)
		(property "Author" "Antmicro"
			(at 196.85 278.13 0)
			(effects
				(font
					(size 1.27 1.27)
					(thickness 0.15)
				)
				(justify left bottom)
				(hide yes)
			)
		)
		(property "License" "Apache-2.0"
			(at 196.85 280.67 0)
			(effects
				(font
					(size 1.27 1.27)
					(thickness 0.15)
				)
				(justify left bottom)
				(hide yes)
			)
		)
		(pin "1"
		)
		(instances
			(project "jetson-agx-thor-baseboard"
				(path ""
					(reference "#PWR0348")
					(unit 1)
				)
			)
		)
	)
	(symbol
		(lib_id "antmicropower:GND")
		(at 66.04 229.87 0)
		(unit 1)
		(exclude_from_sim no)
		(in_bom yes)
		(on_board yes)
		(dnp no)
		(property "Reference" "#PWR0505"
			(at 74.93 232.41 0)
			(effects
				(font
					(size 1.27 1.27)
					(thickness 0.15)
				)
				(justify left bottom)
				(hide yes)
			)
		)
		(property "Value" "GND"
			(at 66.04 233.68 0)
			(effects
				(font
					(size 1.27 1.27)
					(thickness 0.15)
				)
			)
		)
		(property "Footprint" ""
			(at 74.93 237.49 0)
			(effects
				(font
					(size 1.27 1.27)
					(thickness 0.15)
				)
				(justify left bottom)
				(hide yes)
			)
		)
		(property "Datasheet" ""
			(at 74.93 242.57 0)
			(effects
				(font
					(size 1.27 1.27)
					(thickness 0.15)
				)
				(justify left bottom)
				(hide yes)
			)
		)
		(property "Description" ""
			(at 66.04 229.87 0)
			(effects
				(font
					(size 1.27 1.27)
				)
				(hide yes)
			)
		)
		(property "Author" "Antmicro"
			(at 74.93 237.49 0)
			(effects
				(font
					(size 1.27 1.27)
					(thickness 0.15)
				)
				(justify left bottom)
				(hide yes)
			)
		)
		(property "License" "Apache-2.0"
			(at 74.93 240.03 0)
			(effects
				(font
					(size 1.27 1.27)
					(thickness 0.15)
				)
				(justify left bottom)
				(hide yes)
			)
		)
		(pin "1"
		)
		(instances
			(project "jetson-agx-thor-baseboard"
				(path ""
					(reference "#PWR0505")
					(unit 1)
				)
			)
		)
	)
	(symbol
		(lib_id "antmicroCapacitors0402:C_100n_0402")
		(at 279.4 102.87 0)
		(mirror x)
		(unit 1)
		(exclude_from_sim no)
		(in_bom yes)
		(on_board yes)
		(dnp no)
		(property "Reference" "C336"
			(at 288.29 101.6 0)
			(effects
				(font
					(size 1.27 1.27)
				)
				(justify right)
			)
		)
		(property "Value" "C_100n_0402"
			(at 299.72 92.71 0)
			(effects
				(font
					(size 1.27 1.27)
					(thickness 0.15)
				)
				(justify left bottom)
				(hide yes)
			)
		)
		(property "Footprint" "antmicro-footprints:C_0402_1005Metric"
			(at 299.72 90.17 0)
			(effects
				(font
					(size 1.27 1.27)
					(thickness 0.15)
				)
				(justify left bottom)
				(hide yes)
			)
		)
		(property "Datasheet" "https://www.murata.com/products/productdetail?partno=GRM155R61H104KE14%23"
			(at 299.72 87.63 0)
			(effects
				(font
					(size 1.27 1.27)
					(thickness 0.15)
				)
				(justify left bottom)
				(hide yes)
			)
		)
		(property "Description" "SMD Multilayer Ceramic Capacitor, 0.1 µF, 50 V, 0402 [1005 Metric], ± 10%, X5R, GRM Series"
			(at 279.4 102.87 0)
			(effects
				(font
					(size 1.27 1.27)
				)
				(hide yes)
			)
		)
		(property "Manufacturer" "Murata"
			(at 299.72 82.55 0)
			(effects
				(font
					(size 1.27 1.27)
					(thickness 0.15)
				)
				(justify left bottom)
				(hide yes)
			)
		)
		(property "MPN" "GRM155R61H104KE14D"
			(at 299.72 85.09 0)
			(effects
				(font
					(size 1.27 1.27)
					(thickness 0.15)
				)
				(justify left bottom)
				(hide yes)
			)
		)
		(property "Val" "100n"
			(at 280.924 101.854 0)
			(effects
				(font
					(size 1.27 1.27)
					(thickness 0.15)
				)
				(justify right)
			)
		)
		(property "License" "Apache-2.0"
			(at 299.72 80.01 0)
			(effects
				(font
					(size 1.27 1.27)
					(thickness 0.15)
				)
				(justify left bottom)
				(hide yes)
			)
		)
		(property "Author" "Antmicro"
			(at 299.72 77.47 0)
			(effects
				(font
					(size 1.27 1.27)
					(thickness 0.15)
				)
				(justify left bottom)
				(hide yes)
			)
		)
		(property "Voltage" "50V"
			(at 299.72 74.93 0)
			(effects
				(font
					(size 1.27 1.27)
				)
				(justify left bottom)
				(hide yes)
			)
		)
		(property "Dielectric" "X5R"
			(at 299.72 72.39 0)
			(effects
				(font
					(size 1.27 1.27)
				)
				(justify left bottom)
				(hide yes)
			)
		)
		(pin "1"
		)
		(pin "2"
		)
		(instances
			(project "jetson-agx-thor-baseboard"
				(path ""
					(reference "C336")
					(unit 1)
				)
			)
		)
	)
	(symbol
		(lib_id "antmicroCapacitors0402:C_100n_0402")
		(at 287.02 69.85 0)
		(mirror x)
		(unit 1)
		(exclude_from_sim no)
		(in_bom yes)
		(on_board yes)
		(dnp no)
		(property "Reference" "C328"
			(at 295.656 68.58 0)
			(effects
				(font
					(size 1.27 1.27)
				)
				(justify right)
			)
		)
		(property "Value" "C_100n_0402"
			(at 307.34 59.69 0)
			(effects
				(font
					(size 1.27 1.27)
					(thickness 0.15)
				)
				(justify left bottom)
				(hide yes)
			)
		)
		(property "Footprint" "antmicro-footprints:C_0402_1005Metric"
			(at 307.34 57.15 0)
			(effects
				(font
					(size 1.27 1.27)
					(thickness 0.15)
				)
				(justify left bottom)
				(hide yes)
			)
		)
		(property "Datasheet" "https://www.murata.com/products/productdetail?partno=GRM155R61H104KE14%23"
			(at 307.34 54.61 0)
			(effects
				(font
					(size 1.27 1.27)
					(thickness 0.15)
				)
				(justify left bottom)
				(hide yes)
			)
		)
		(property "Description" "SMD Multilayer Ceramic Capacitor, 0.1 µF, 50 V, 0402 [1005 Metric], ± 10%, X5R, GRM Series"
			(at 287.02 69.85 0)
			(effects
				(font
					(size 1.27 1.27)
				)
				(hide yes)
			)
		)
		(property "Manufacturer" "Murata"
			(at 307.34 49.53 0)
			(effects
				(font
					(size 1.27 1.27)
					(thickness 0.15)
				)
				(justify left bottom)
				(hide yes)
			)
		)
		(property "MPN" "GRM155R61H104KE14D"
			(at 307.34 52.07 0)
			(effects
				(font
					(size 1.27 1.27)
					(thickness 0.15)
				)
				(justify left bottom)
				(hide yes)
			)
		)
		(property "Val" "100n"
			(at 288.544 68.834 0)
			(effects
				(font
					(size 1.27 1.27)
					(thickness 0.15)
				)
				(justify right)
			)
		)
		(property "License" "Apache-2.0"
			(at 307.34 46.99 0)
			(effects
				(font
					(size 1.27 1.27)
					(thickness 0.15)
				)
				(justify left bottom)
				(hide yes)
			)
		)
		(property "Author" "Antmicro"
			(at 307.34 44.45 0)
			(effects
				(font
					(size 1.27 1.27)
					(thickness 0.15)
				)
				(justify left bottom)
				(hide yes)
			)
		)
		(property "Voltage" "50V"
			(at 307.34 41.91 0)
			(effects
				(font
					(size 1.27 1.27)
				)
				(justify left bottom)
				(hide yes)
			)
		)
		(property "Dielectric" "X5R"
			(at 307.34 39.37 0)
			(effects
				(font
					(size 1.27 1.27)
				)
				(justify left bottom)
				(hide yes)
			)
		)
		(pin "1"
		)
		(pin "2"
		)
		(instances
			(project "jetson-agx-thor-baseboard"
				(path ""
					(reference "C328")
					(unit 1)
				)
			)
		)
	)
	(symbol
		(lib_id "antmicroCapacitors0402:C_100n_0402")
		(at 287.02 120.65 0)
		(mirror x)
		(unit 1)
		(exclude_from_sim no)
		(in_bom yes)
		(on_board yes)
		(dnp no)
		(property "Reference" "C348"
			(at 295.656 119.38 0)
			(effects
				(font
					(size 1.27 1.27)
				)
				(justify right)
			)
		)
		(property "Value" "C_100n_0402"
			(at 307.34 110.49 0)
			(effects
				(font
					(size 1.27 1.27)
					(thickness 0.15)
				)
				(justify left bottom)
				(hide yes)
			)
		)
		(property "Footprint" "antmicro-footprints:C_0402_1005Metric"
			(at 307.34 107.95 0)
			(effects
				(font
					(size 1.27 1.27)
					(thickness 0.15)
				)
				(justify left bottom)
				(hide yes)
			)
		)
		(property "Datasheet" "https://www.murata.com/products/productdetail?partno=GRM155R61H104KE14%23"
			(at 307.34 105.41 0)
			(effects
				(font
					(size 1.27 1.27)
					(thickness 0.15)
				)
				(justify left bottom)
				(hide yes)
			)
		)
		(property "Description" "SMD Multilayer Ceramic Capacitor, 0.1 µF, 50 V, 0402 [1005 Metric], ± 10%, X5R, GRM Series"
			(at 287.02 120.65 0)
			(effects
				(font
					(size 1.27 1.27)
				)
				(hide yes)
			)
		)
		(property "Manufacturer" "Murata"
			(at 307.34 100.33 0)
			(effects
				(font
					(size 1.27 1.27)
					(thickness 0.15)
				)
				(justify left bottom)
				(hide yes)
			)
		)
		(property "MPN" "GRM155R61H104KE14D"
			(at 307.34 102.87 0)
			(effects
				(font
					(size 1.27 1.27)
					(thickness 0.15)
				)
				(justify left bottom)
				(hide yes)
			)
		)
		(property "Val" "100n"
			(at 288.544 119.634 0)
			(effects
				(font
					(size 1.27 1.27)
					(thickness 0.15)
				)
				(justify right)
			)
		)
		(property "License" "Apache-2.0"
			(at 307.34 97.79 0)
			(effects
				(font
					(size 1.27 1.27)
					(thickness 0.15)
				)
				(justify left bottom)
				(hide yes)
			)
		)
		(property "Author" "Antmicro"
			(at 307.34 95.25 0)
			(effects
				(font
					(size 1.27 1.27)
					(thickness 0.15)
				)
				(justify left bottom)
				(hide yes)
			)
		)
		(property "Voltage" "50V"
			(at 307.34 92.71 0)
			(effects
				(font
					(size 1.27 1.27)
				)
				(justify left bottom)
				(hide yes)
			)
		)
		(property "Dielectric" "X5R"
			(at 307.34 90.17 0)
			(effects
				(font
					(size 1.27 1.27)
				)
				(justify left bottom)
				(hide yes)
			)
		)
		(pin "1"
		)
		(pin "2"
		)
		(instances
			(project "jetson-agx-thor-baseboard"
				(path ""
					(reference "C348")
					(unit 1)
				)
			)
		)
	)
	(symbol
		(lib_id "antmicroCapacitors0402:C_100n_0402")
		(at 279.4 72.39 0)
		(mirror x)
		(unit 1)
		(exclude_from_sim no)
		(in_bom yes)
		(on_board yes)
		(dnp no)
		(property "Reference" "C325"
			(at 288.29 71.12 0)
			(effects
				(font
					(size 1.27 1.27)
				)
				(justify right)
			)
		)
		(property "Value" "C_100n_0402"
			(at 299.72 62.23 0)
			(effects
				(font
					(size 1.27 1.27)
					(thickness 0.15)
				)
				(justify left bottom)
				(hide yes)
			)
		)
		(property "Footprint" "antmicro-footprints:C_0402_1005Metric"
			(at 299.72 59.69 0)
			(effects
				(font
					(size 1.27 1.27)
					(thickness 0.15)
				)
				(justify left bottom)
				(hide yes)
			)
		)
		(property "Datasheet" "https://www.murata.com/products/productdetail?partno=GRM155R61H104KE14%23"
			(at 299.72 57.15 0)
			(effects
				(font
					(size 1.27 1.27)
					(thickness 0.15)
				)
				(justify left bottom)
				(hide yes)
			)
		)
		(property "Description" "SMD Multilayer Ceramic Capacitor, 0.1 µF, 50 V, 0402 [1005 Metric], ± 10%, X5R, GRM Series"
			(at 279.4 72.39 0)
			(effects
				(font
					(size 1.27 1.27)
				)
				(hide yes)
			)
		)
		(property "Manufacturer" "Murata"
			(at 299.72 52.07 0)
			(effects
				(font
					(size 1.27 1.27)
					(thickness 0.15)
				)
				(justify left bottom)
				(hide yes)
			)
		)
		(property "MPN" "GRM155R61H104KE14D"
			(at 299.72 54.61 0)
			(effects
				(font
					(size 1.27 1.27)
					(thickness 0.15)
				)
				(justify left bottom)
				(hide yes)
			)
		)
		(property "Val" "100n"
			(at 280.924 71.374 0)
			(effects
				(font
					(size 1.27 1.27)
					(thickness 0.15)
				)
				(justify right)
			)
		)
		(property "License" "Apache-2.0"
			(at 299.72 49.53 0)
			(effects
				(font
					(size 1.27 1.27)
					(thickness 0.15)
				)
				(justify left bottom)
				(hide yes)
			)
		)
		(property "Author" "Antmicro"
			(at 299.72 46.99 0)
			(effects
				(font
					(size 1.27 1.27)
					(thickness 0.15)
				)
				(justify left bottom)
				(hide yes)
			)
		)
		(property "Voltage" "50V"
			(at 299.72 44.45 0)
			(effects
				(font
					(size 1.27 1.27)
				)
				(justify left bottom)
				(hide yes)
			)
		)
		(property "Dielectric" "X5R"
			(at 299.72 41.91 0)
			(effects
				(font
					(size 1.27 1.27)
				)
				(justify left bottom)
				(hide yes)
			)
		)
		(pin "1"
		)
		(pin "2"
		)
		(instances
			(project "jetson-agx-thor-baseboard"
				(path ""
					(reference "C325")
					(unit 1)
				)
			)
		)
	)
	(symbol
		(lib_id "antmicroCapacitors0402:C_100n_0402")
		(at 279.4 123.19 0)
		(mirror x)
		(unit 1)
		(exclude_from_sim no)
		(in_bom yes)
		(on_board yes)
		(dnp no)
		(property "Reference" "C345"
			(at 288.29 121.92 0)
			(effects
				(font
					(size 1.27 1.27)
				)
				(justify right)
			)
		)
		(property "Value" "C_100n_0402"
			(at 299.72 113.03 0)
			(effects
				(font
					(size 1.27 1.27)
					(thickness 0.15)
				)
				(justify left bottom)
				(hide yes)
			)
		)
		(property "Footprint" "antmicro-footprints:C_0402_1005Metric"
			(at 299.72 110.49 0)
			(effects
				(font
					(size 1.27 1.27)
					(thickness 0.15)
				)
				(justify left bottom)
				(hide yes)
			)
		)
		(property "Datasheet" "https://www.murata.com/products/productdetail?partno=GRM155R61H104KE14%23"
			(at 299.72 107.95 0)
			(effects
				(font
					(size 1.27 1.27)
					(thickness 0.15)
				)
				(justify left bottom)
				(hide yes)
			)
		)
		(property "Description" "SMD Multilayer Ceramic Capacitor, 0.1 µF, 50 V, 0402 [1005 Metric], ± 10%, X5R, GRM Series"
			(at 279.4 123.19 0)
			(effects
				(font
					(size 1.27 1.27)
				)
				(hide yes)
			)
		)
		(property "Manufacturer" "Murata"
			(at 299.72 102.87 0)
			(effects
				(font
					(size 1.27 1.27)
					(thickness 0.15)
				)
				(justify left bottom)
				(hide yes)
			)
		)
		(property "MPN" "GRM155R61H104KE14D"
			(at 299.72 105.41 0)
			(effects
				(font
					(size 1.27 1.27)
					(thickness 0.15)
				)
				(justify left bottom)
				(hide yes)
			)
		)
		(property "Val" "100n"
			(at 280.924 122.174 0)
			(effects
				(font
					(size 1.27 1.27)
					(thickness 0.15)
				)
				(justify right)
			)
		)
		(property "License" "Apache-2.0"
			(at 299.72 100.33 0)
			(effects
				(font
					(size 1.27 1.27)
					(thickness 0.15)
				)
				(justify left bottom)
				(hide yes)
			)
		)
		(property "Author" "Antmicro"
			(at 299.72 97.79 0)
			(effects
				(font
					(size 1.27 1.27)
					(thickness 0.15)
				)
				(justify left bottom)
				(hide yes)
			)
		)
		(property "Voltage" "50V"
			(at 299.72 95.25 0)
			(effects
				(font
					(size 1.27 1.27)
				)
				(justify left bottom)
				(hide yes)
			)
		)
		(property "Dielectric" "X5R"
			(at 299.72 92.71 0)
			(effects
				(font
					(size 1.27 1.27)
				)
				(justify left bottom)
				(hide yes)
			)
		)
		(pin "1"
		)
		(pin "2"
		)
		(instances
			(project "jetson-agx-thor-baseboard"
				(path ""
					(reference "C345")
					(unit 1)
				)
			)
		)
	)
	(symbol
		(lib_id "antmicroResistors0402:R_0R_0402")
		(at 62.23 238.76 0)
		(mirror y)
		(unit 1)
		(exclude_from_sim no)
		(in_bom no)
		(on_board yes)
		(dnp yes)
		(property "Reference" "R294"
			(at 64.77 237.49 0)
			(effects
				(font
					(size 1.27 1.27)
					(thickness 0.15)
				)
			)
		)
		(property "Value" "R_0R_0402"
			(at 41.91 251.46 0)
			(effects
				(font
					(size 1.27 1.27)
					(thickness 0.15)
				)
				(justify left bottom)
				(hide yes)
			)
		)
		(property "Footprint" "antmicro-footprints:R_0402_1005Metric"
			(at 41.91 254 0)
			(effects
				(font
					(size 1.27 1.27)
					(thickness 0.15)
				)
				(justify left bottom)
				(hide yes)
			)
		)
		(property "Datasheet" "https://industrial.panasonic.com/cdbs/www-data/pdf/RDA0000/AOA0000C301.pdf"
			(at 41.91 256.54 0)
			(effects
				(font
					(size 1.27 1.27)
					(thickness 0.15)
				)
				(justify left bottom)
				(hide yes)
			)
		)
		(property "Description" "SMD Chip Resistor, Jumper, 0 ohm, 100 mW, 0402 [1005 Metric], Thick Film, General Purpose"
			(at 62.23 238.76 0)
			(effects
				(font
					(size 1.27 1.27)
				)
				(hide yes)
			)
		)
		(property "MPN" "ERJ2GE0R00X"
			(at 41.91 259.08 0)
			(effects
				(font
					(size 1.27 1.27)
					(thickness 0.15)
				)
				(justify left bottom)
				(hide yes)
			)
		)
		(property "Manufacturer" "Panasonic"
			(at 41.91 261.62 0)
			(effects
				(font
					(size 1.27 1.27)
					(thickness 0.15)
				)
				(justify left bottom)
				(hide yes)
			)
		)
		(property "License" "Apache-2.0"
			(at 41.91 264.16 0)
			(effects
				(font
					(size 1.27 1.27)
					(thickness 0.15)
				)
				(justify left bottom)
				(hide yes)
			)
		)
		(property "Author" "Antmicro"
			(at 41.91 266.7 0)
			(effects
				(font
					(size 1.27 1.27)
					(thickness 0.15)
				)
				(justify left bottom)
				(hide yes)
			)
		)
		(property "Val" "0R"
			(at 55.88 237.49 0)
			(effects
				(font
					(size 1.27 1.27)
					(thickness 0.15)
				)
			)
		)
		(property "Tolerance" "~"
			(at 41.91 248.92 0)
			(effects
				(font
					(size 1.27 1.27)
				)
				(justify left bottom)
				(hide yes)
			)
		)
		(property "Current" "1A"
			(at 41.91 269.24 0)
			(effects
				(font
					(size 1.27 1.27)
					(thickness 0.15)
				)
				(justify left bottom)
				(hide yes)
			)
		)
		(pin "2"
		)
		(pin "1"
		)
		(instances
			(project "jetson-agx-thor-baseboard"
				(path ""
					(reference "R294")
					(unit 1)
				)
			)
		)
	)
	(symbol
		(lib_id "antmicropower:+3V3")
		(at 205.74 233.68 0)
		(unit 1)
		(exclude_from_sim no)
		(in_bom yes)
		(on_board yes)
		(dnp no)
		(fields_autoplaced yes)
		(property "Reference" "#PWR028"
			(at 220.98 233.68 0)
			(effects
				(font
					(size 1.27 1.27)
					(thickness 0.15)
				)
				(justify left bottom)
				(hide yes)
			)
		)
		(property "Value" "+3V3"
			(at 205.74 228.6 0)
			(effects
				(font
					(size 1.27 1.27)
					(thickness 0.15)
				)
			)
		)
		(property "Footprint" ""
			(at 220.98 241.3 0)
			(effects
				(font
					(size 1.27 1.27)
					(thickness 0.15)
				)
				(justify left bottom)
				(hide yes)
			)
		)
		(property "Datasheet" ""
			(at 220.98 243.84 0)
			(effects
				(font
					(size 1.27 1.27)
					(thickness 0.15)
				)
				(justify left bottom)
				(hide yes)
			)
		)
		(property "Description" ""
			(at 205.74 233.68 0)
			(effects
				(font
					(size 1.27 1.27)
				)
				(hide yes)
			)
		)
		(property "Author" "Antmicro"
			(at 220.98 236.22 0)
			(effects
				(font
					(size 1.27 1.27)
					(thickness 0.15)
				)
				(justify left bottom)
				(hide yes)
			)
		)
		(property "License" "Apache-2.0"
			(at 220.98 238.76 0)
			(effects
				(font
					(size 1.27 1.27)
					(thickness 0.15)
				)
				(justify left bottom)
				(hide yes)
			)
		)
		(pin "1"
		)
		(instances
			(project "jetson-agx-thor-baseboard"
				(path ""
					(reference "#PWR028")
					(unit 1)
				)
			)
		)
	)
	(symbol
		(lib_id "antmicroResistors0402:R_0R_0402")
		(at 46.99 77.47 0)
		(unit 1)
		(exclude_from_sim no)
		(in_bom no)
		(on_board yes)
		(dnp yes)
		(property "Reference" "R195"
			(at 43.942 76.2 0)
			(effects
				(font
					(size 1.27 1.27)
					(thickness 0.15)
				)
			)
		)
		(property "Value" "R_0R_0402"
			(at 67.31 90.17 0)
			(effects
				(font
					(size 1.27 1.27)
					(thickness 0.15)
				)
				(justify left bottom)
				(hide yes)
			)
		)
		(property "Footprint" "antmicro-footprints:R_0402_1005Metric"
			(at 67.31 92.71 0)
			(effects
				(font
					(size 1.27 1.27)
					(thickness 0.15)
				)
				(justify left bottom)
				(hide yes)
			)
		)
		(property "Datasheet" "https://industrial.panasonic.com/cdbs/www-data/pdf/RDA0000/AOA0000C301.pdf"
			(at 67.31 95.25 0)
			(effects
				(font
					(size 1.27 1.27)
					(thickness 0.15)
				)
				(justify left bottom)
				(hide yes)
			)
		)
		(property "Description" "SMD Chip Resistor, Jumper, 0 ohm, 100 mW, 0402 [1005 Metric], Thick Film, General Purpose"
			(at 46.99 77.47 0)
			(effects
				(font
					(size 1.27 1.27)
				)
				(hide yes)
			)
		)
		(property "MPN" "ERJ2GE0R00X"
			(at 67.31 97.79 0)
			(effects
				(font
					(size 1.27 1.27)
					(thickness 0.15)
				)
				(justify left bottom)
				(hide yes)
			)
		)
		(property "Manufacturer" "Panasonic"
			(at 67.31 100.33 0)
			(effects
				(font
					(size 1.27 1.27)
					(thickness 0.15)
				)
				(justify left bottom)
				(hide yes)
			)
		)
		(property "License" "Apache-2.0"
			(at 67.31 102.87 0)
			(effects
				(font
					(size 1.27 1.27)
					(thickness 0.15)
				)
				(justify left bottom)
				(hide yes)
			)
		)
		(property "Author" "Antmicro"
			(at 67.31 105.41 0)
			(effects
				(font
					(size 1.27 1.27)
					(thickness 0.15)
				)
				(justify left bottom)
				(hide yes)
			)
		)
		(property "Val" "0R"
			(at 53.34 76.2 0)
			(effects
				(font
					(size 1.27 1.27)
					(thickness 0.15)
				)
			)
		)
		(property "Tolerance" "~"
			(at 67.31 87.63 0)
			(effects
				(font
					(size 1.27 1.27)
				)
				(justify left bottom)
				(hide yes)
			)
		)
		(property "Current" "1A"
			(at 67.31 107.95 0)
			(effects
				(font
					(size 1.27 1.27)
					(thickness 0.15)
				)
				(justify left bottom)
				(hide yes)
			)
		)
		(pin "1"
		)
		(pin "2"
		)
		(instances
			(project "jetson-agx-thor-baseboard"
				(path ""
					(reference "R195")
					(unit 1)
				)
			)
		)
	)
	(symbol
		(lib_id "antmicropower:GND")
		(at 116.84 278.13 0)
		(mirror y)
		(unit 1)
		(exclude_from_sim no)
		(in_bom yes)
		(on_board yes)
		(dnp no)
		(property "Reference" "#PWR0502"
			(at 107.95 280.67 0)
			(effects
				(font
					(size 1.27 1.27)
					(thickness 0.15)
				)
				(justify left bottom)
				(hide yes)
			)
		)
		(property "Value" "GND"
			(at 116.84 281.94 0)
			(effects
				(font
					(size 1.27 1.27)
					(thickness 0.15)
				)
			)
		)
		(property "Footprint" ""
			(at 107.95 285.75 0)
			(effects
				(font
					(size 1.27 1.27)
					(thickness 0.15)
				)
				(justify left bottom)
				(hide yes)
			)
		)
		(property "Datasheet" ""
			(at 107.95 290.83 0)
			(effects
				(font
					(size 1.27 1.27)
					(thickness 0.15)
				)
				(justify left bottom)
				(hide yes)
			)
		)
		(property "Description" ""
			(at 116.84 278.13 0)
			(effects
				(font
					(size 1.27 1.27)
				)
				(hide yes)
			)
		)
		(property "Author" "Antmicro"
			(at 107.95 285.75 0)
			(effects
				(font
					(size 1.27 1.27)
					(thickness 0.15)
				)
				(justify left bottom)
				(hide yes)
			)
		)
		(property "License" "Apache-2.0"
			(at 107.95 288.29 0)
			(effects
				(font
					(size 1.27 1.27)
					(thickness 0.15)
				)
				(justify left bottom)
				(hide yes)
			)
		)
		(pin "1"
		)
		(instances
			(project "jetson-agx-thor-baseboard"
				(path ""
					(reference "#PWR0502")
					(unit 1)
				)
			)
		)
	)
	(symbol
		(lib_id "antmicropower:GND")
		(at 274.32 245.11 0)
		(unit 1)
		(exclude_from_sim no)
		(in_bom yes)
		(on_board yes)
		(dnp no)
		(property "Reference" "#PWR032"
			(at 283.21 247.65 0)
			(effects
				(font
					(size 1.27 1.27)
					(thickness 0.15)
				)
				(justify left bottom)
				(hide yes)
			)
		)
		(property "Value" "GND"
			(at 274.32 248.92 0)
			(effects
				(font
					(size 1.27 1.27)
					(thickness 0.15)
				)
			)
		)
		(property "Footprint" ""
			(at 283.21 252.73 0)
			(effects
				(font
					(size 1.27 1.27)
					(thickness 0.15)
				)
				(justify left bottom)
				(hide yes)
			)
		)
		(property "Datasheet" ""
			(at 283.21 257.81 0)
			(effects
				(font
					(size 1.27 1.27)
					(thickness 0.15)
				)
				(justify left bottom)
				(hide yes)
			)
		)
		(property "Description" ""
			(at 274.32 245.11 0)
			(effects
				(font
					(size 1.27 1.27)
				)
				(hide yes)
			)
		)
		(property "Author" "Antmicro"
			(at 283.21 252.73 0)
			(effects
				(font
					(size 1.27 1.27)
					(thickness 0.15)
				)
				(justify left bottom)
				(hide yes)
			)
		)
		(property "License" "Apache-2.0"
			(at 283.21 255.27 0)
			(effects
				(font
					(size 1.27 1.27)
					(thickness 0.15)
				)
				(justify left bottom)
				(hide yes)
			)
		)
		(pin "1"
		)
		(instances
			(project "jetson-agx-thor-baseboard"
				(path ""
					(reference "#PWR032")
					(unit 1)
				)
			)
		)
	)
	(symbol
		(lib_id "antmicropower:GND")
		(at 266.7 245.11 0)
		(unit 1)
		(exclude_from_sim no)
		(in_bom yes)
		(on_board yes)
		(dnp no)
		(property "Reference" "#PWR031"
			(at 275.59 247.65 0)
			(effects
				(font
					(size 1.27 1.27)
					(thickness 0.15)
				)
				(justify left bottom)
				(hide yes)
			)
		)
		(property "Value" "GND"
			(at 266.7 248.92 0)
			(effects
				(font
					(size 1.27 1.27)
					(thickness 0.15)
				)
			)
		)
		(property "Footprint" ""
			(at 275.59 252.73 0)
			(effects
				(font
					(size 1.27 1.27)
					(thickness 0.15)
				)
				(justify left bottom)
				(hide yes)
			)
		)
		(property "Datasheet" ""
			(at 275.59 257.81 0)
			(effects
				(font
					(size 1.27 1.27)
					(thickness 0.15)
				)
				(justify left bottom)
				(hide yes)
			)
		)
		(property "Description" ""
			(at 266.7 245.11 0)
			(effects
				(font
					(size 1.27 1.27)
				)
				(hide yes)
			)
		)
		(property "Author" "Antmicro"
			(at 275.59 252.73 0)
			(effects
				(font
					(size 1.27 1.27)
					(thickness 0.15)
				)
				(justify left bottom)
				(hide yes)
			)
		)
		(property "License" "Apache-2.0"
			(at 275.59 255.27 0)
			(effects
				(font
					(size 1.27 1.27)
					(thickness 0.15)
				)
				(justify left bottom)
				(hide yes)
			)
		)
		(pin "1"
		)
		(instances
			(project "jetson-agx-thor-baseboard"
				(path ""
					(reference "#PWR031")
					(unit 1)
				)
			)
		)
	)
	(symbol
		(lib_id "antmicroResistors0402:R_33R_0402")
		(at 257.81 234.95 0)
		(unit 1)
		(exclude_from_sim no)
		(in_bom yes)
		(on_board yes)
		(dnp no)
		(property "Reference" "R2"
			(at 255.27 233.68 0)
			(effects
				(font
					(size 1.27 1.27)
					(thickness 0.15)
				)
			)
		)
		(property "Value" "R_33R_0402"
			(at 278.13 247.65 0)
			(effects
				(font
					(size 1.27 1.27)
					(thickness 0.15)
				)
				(justify left bottom)
				(hide yes)
			)
		)
		(property "Footprint" "antmicro-footprints:R_0402_1005Metric"
			(at 278.13 250.19 0)
			(effects
				(font
					(size 1.27 1.27)
					(thickness 0.15)
				)
				(justify left bottom)
				(hide yes)
			)
		)
		(property "Datasheet" "https://www.bourns.com/docs/product-datasheets/cr.pdf"
			(at 278.13 252.73 0)
			(effects
				(font
					(size 1.27 1.27)
					(thickness 0.15)
				)
				(justify left bottom)
				(hide yes)
			)
		)
		(property "Description" "SMD Chip Resistor, 33 ohm, ± 1%, 62.5 mW, 0402 [1005 Metric], Thick Film, General Purpose"
			(at 257.81 234.95 0)
			(effects
				(font
					(size 1.27 1.27)
				)
				(hide yes)
			)
		)
		(property "MPN" "CR0402-FX-33R0GLF"
			(at 278.13 255.27 0)
			(effects
				(font
					(size 1.27 1.27)
					(thickness 0.15)
				)
				(justify left bottom)
				(hide yes)
			)
		)
		(property "Manufacturer" "Bourns"
			(at 278.13 257.81 0)
			(effects
				(font
					(size 1.27 1.27)
					(thickness 0.15)
				)
				(justify left bottom)
				(hide yes)
			)
		)
		(property "License" "Apache-2.0"
			(at 278.13 260.35 0)
			(effects
				(font
					(size 1.27 1.27)
					(thickness 0.15)
				)
				(justify left bottom)
				(hide yes)
			)
		)
		(property "Author" "Antmicro"
			(at 278.13 262.89 0)
			(effects
				(font
					(size 1.27 1.27)
					(thickness 0.15)
				)
				(justify left bottom)
				(hide yes)
			)
		)
		(property "Val" "33R"
			(at 264.795 233.68 0)
			(effects
				(font
					(size 1.27 1.27)
					(thickness 0.15)
				)
			)
		)
		(property "Tolerance" "1%"
			(at 278.13 245.11 0)
			(effects
				(font
					(size 1.27 1.27)
				)
				(justify left bottom)
				(hide yes)
			)
		)
		(pin "2"
		)
		(pin "1"
		)
		(instances
			(project "jetson-agx-thor-baseboard"
				(path ""
					(reference "R2")
					(unit 1)
				)
			)
		)
	)
	(symbol
		(lib_id "antmicropower:GND")
		(at 96.52 250.19 0)
		(mirror y)
		(unit 1)
		(exclude_from_sim no)
		(in_bom yes)
		(on_board yes)
		(dnp no)
		(property "Reference" "#PWR0500"
			(at 87.63 252.73 0)
			(effects
				(font
					(size 1.27 1.27)
					(thickness 0.15)
				)
				(justify left bottom)
				(hide yes)
			)
		)
		(property "Value" "GND"
			(at 96.52 254 0)
			(effects
				(font
					(size 1.27 1.27)
					(thickness 0.15)
				)
			)
		)
		(property "Footprint" ""
			(at 87.63 257.81 0)
			(effects
				(font
					(size 1.27 1.27)
					(thickness 0.15)
				)
				(justify left bottom)
				(hide yes)
			)
		)
		(property "Datasheet" ""
			(at 87.63 262.89 0)
			(effects
				(font
					(size 1.27 1.27)
					(thickness 0.15)
				)
				(justify left bottom)
				(hide yes)
			)
		)
		(property "Description" ""
			(at 96.52 250.19 0)
			(effects
				(font
					(size 1.27 1.27)
				)
				(hide yes)
			)
		)
		(property "Author" "Antmicro"
			(at 87.63 257.81 0)
			(effects
				(font
					(size 1.27 1.27)
					(thickness 0.15)
				)
				(justify left bottom)
				(hide yes)
			)
		)
		(property "License" "Apache-2.0"
			(at 87.63 260.35 0)
			(effects
				(font
					(size 1.27 1.27)
					(thickness 0.15)
				)
				(justify left bottom)
				(hide yes)
			)
		)
		(pin "1"
		)
		(instances
			(project "jetson-agx-thor-baseboard"
				(path ""
					(reference "#PWR0500")
					(unit 1)
				)
			)
		)
	)
	(symbol
		(lib_id "antmicroCapacitors0402:C_100n_0402")
		(at 365.76 107.95 0)
		(mirror x)
		(unit 1)
		(exclude_from_sim no)
		(in_bom yes)
		(on_board yes)
		(dnp no)
		(property "Reference" "C342"
			(at 374.65 106.68 0)
			(effects
				(font
					(size 1.27 1.27)
				)
				(justify right)
			)
		)
		(property "Value" "C_100n_0402"
			(at 386.08 97.79 0)
			(effects
				(font
					(size 1.27 1.27)
					(thickness 0.15)
				)
				(justify left bottom)
				(hide yes)
			)
		)
		(property "Footprint" "antmicro-footprints:C_0402_1005Metric"
			(at 386.08 95.25 0)
			(effects
				(font
					(size 1.27 1.27)
					(thickness 0.15)
				)
				(justify left bottom)
				(hide yes)
			)
		)
		(property "Datasheet" "https://www.murata.com/products/productdetail?partno=GRM155R61H104KE14%23"
			(at 386.08 92.71 0)
			(effects
				(font
					(size 1.27 1.27)
					(thickness 0.15)
				)
				(justify left bottom)
				(hide yes)
			)
		)
		(property "Description" "SMD Multilayer Ceramic Capacitor, 0.1 µF, 50 V, 0402 [1005 Metric], ± 10%, X5R, GRM Series"
			(at 365.76 107.95 0)
			(effects
				(font
					(size 1.27 1.27)
				)
				(hide yes)
			)
		)
		(property "Manufacturer" "Murata"
			(at 386.08 87.63 0)
			(effects
				(font
					(size 1.27 1.27)
					(thickness 0.15)
				)
				(justify left bottom)
				(hide yes)
			)
		)
		(property "MPN" "GRM155R61H104KE14D"
			(at 386.08 90.17 0)
			(effects
				(font
					(size 1.27 1.27)
					(thickness 0.15)
				)
				(justify left bottom)
				(hide yes)
			)
		)
		(property "Val" "100n"
			(at 367.284 106.934 0)
			(effects
				(font
					(size 1.27 1.27)
					(thickness 0.15)
				)
				(justify right)
			)
		)
		(property "License" "Apache-2.0"
			(at 386.08 85.09 0)
			(effects
				(font
					(size 1.27 1.27)
					(thickness 0.15)
				)
				(justify left bottom)
				(hide yes)
			)
		)
		(property "Author" "Antmicro"
			(at 386.08 82.55 0)
			(effects
				(font
					(size 1.27 1.27)
					(thickness 0.15)
				)
				(justify left bottom)
				(hide yes)
			)
		)
		(property "Voltage" "50V"
			(at 386.08 80.01 0)
			(effects
				(font
					(size 1.27 1.27)
				)
				(justify left bottom)
				(hide yes)
			)
		)
		(property "Dielectric" "X5R"
			(at 386.08 77.47 0)
			(effects
				(font
					(size 1.27 1.27)
				)
				(justify left bottom)
				(hide yes)
			)
		)
		(pin "1"
		)
		(pin "2"
		)
		(instances
			(project "jetson-agx-thor-baseboard"
				(path ""
					(reference "C342")
					(unit 1)
				)
			)
		)
	)
	(symbol
		(lib_id "antmicroTestPoints:Tag-Connect_TC2050-IDC-NL_2x5_P1.27mm")
		(at 137.16 233.68 0)
		(unit 1)
		(exclude_from_sim no)
		(in_bom no)
		(on_board yes)
		(dnp no)
		(property "Reference" "J20"
			(at 151.765 226.06 0)
			(effects
				(font
					(size 1.27 1.27)
					(thickness 0.15)
				)
			)
		)
		(property "Value" "Tag-Connect_TC2050-IDC-NL_2x5_P1.27mm"
			(at 175.26 237.49 0)
			(effects
				(font
					(size 1.27 1.27)
					(thickness 0.15)
				)
				(justify left bottom)
				(hide yes)
			)
		)
		(property "Footprint" "antmicro-footprints:Tag-Connect_TC2050-IDC-NL_2x5_P1.27mm"
			(at 175.26 240.03 0)
			(effects
				(font
					(size 1.27 1.27)
					(thickness 0.15)
				)
				(justify left bottom)
				(hide yes)
			)
		)
		(property "Datasheet" "https://www.tag-connect.com/wp-content/uploads/bsk-pdf-manager/TC2050-IDC-NL_Datasheet_8.pdf"
			(at 175.26 242.57 0)
			(effects
				(font
					(size 1.27 1.27)
					(thickness 0.15)
				)
				(justify left bottom)
				(hide yes)
			)
		)
		(property "Description" "Tag Connect 2x5 1.27mm terminal"
			(at 137.16 233.68 0)
			(effects
				(font
					(size 1.27 1.27)
				)
				(hide yes)
			)
		)
		(property "MPN" "TC2050-IDC-NL"
			(at 151.765 228.6 0)
			(effects
				(font
					(size 1.27 1.27)
					(thickness 0.15)
				)
			)
		)
		(property "Manufacturer" "Tag Connect"
			(at 175.26 247.65 0)
			(effects
				(font
					(size 1.27 1.27)
					(thickness 0.15)
				)
				(justify left bottom)
				(hide yes)
			)
		)
		(property "Author" "Antmicro"
			(at 175.26 250.19 0)
			(effects
				(font
					(size 1.27 1.27)
					(thickness 0.15)
				)
				(justify left bottom)
				(hide yes)
			)
		)
		(property "License" "Apache-2.0"
			(at 175.26 252.73 0)
			(effects
				(font
					(size 1.27 1.27)
					(thickness 0.15)
				)
				(justify left bottom)
				(hide yes)
			)
		)
		(pin "8"
		)
		(pin "9"
		)
		(pin "2"
		)
		(pin "7"
		)
		(pin "10"
		)
		(pin "1"
		)
		(pin "5"
		)
		(pin "6"
		)
		(pin "3"
		)
		(pin "4"
		)
		(instances
			(project "jetson-agx-thor-baseboard"
				(path ""
					(reference "J20")
					(unit 1)
				)
			)
		)
	)
	(symbol
		(lib_id "antmicroResistors0402:R_49R9_0402")
		(at 266.7 273.05 90)
		(unit 1)
		(exclude_from_sim no)
		(in_bom yes)
		(on_board yes)
		(dnp no)
		(property "Reference" "R191"
			(at 267.97 269.24 90)
			(effects
				(font
					(size 1.27 1.27)
					(thickness 0.15)
				)
				(justify right)
			)
		)
		(property "Value" "R_49R9_0402"
			(at 279.4 252.73 0)
			(effects
				(font
					(size 1.27 1.27)
					(thickness 0.15)
				)
				(justify left bottom)
				(hide yes)
			)
		)
		(property "Footprint" "antmicro-footprints:R_0402_1005Metric"
			(at 281.94 252.73 0)
			(effects
				(font
					(size 1.27 1.27)
					(thickness 0.15)
				)
				(justify left bottom)
				(hide yes)
			)
		)
		(property "Datasheet" "https://www.bourns.com/docs/product-datasheets/cr.pdf"
			(at 284.48 252.73 0)
			(effects
				(font
					(size 1.27 1.27)
					(thickness 0.15)
				)
				(justify left bottom)
				(hide yes)
			)
		)
		(property "Description" "SMD Chip Resistor, 49.9 ohm, ± 1%, 62.5 mW, 0402 [1005 Metric], Thick Film, General Purpose"
			(at 266.7 273.05 0)
			(effects
				(font
					(size 1.27 1.27)
				)
				(hide yes)
			)
		)
		(property "MPN" "CR0402-FX-49R9GLF"
			(at 287.02 252.73 0)
			(effects
				(font
					(size 1.27 1.27)
					(thickness 0.15)
				)
				(justify left bottom)
				(hide yes)
			)
		)
		(property "Manufacturer" "Bourns"
			(at 289.56 252.73 0)
			(effects
				(font
					(size 1.27 1.27)
					(thickness 0.15)
				)
				(justify left bottom)
				(hide yes)
			)
		)
		(property "License" "Apache-2.0"
			(at 292.1 252.73 0)
			(effects
				(font
					(size 1.27 1.27)
					(thickness 0.15)
				)
				(justify left bottom)
				(hide yes)
			)
		)
		(property "Author" "Antmicro"
			(at 294.64 252.73 0)
			(effects
				(font
					(size 1.27 1.27)
					(thickness 0.15)
				)
				(justify left bottom)
				(hide yes)
			)
		)
		(property "Val" "49R9"
			(at 267.97 271.78 90)
			(effects
				(font
					(size 1.27 1.27)
					(thickness 0.15)
				)
				(justify right)
			)
		)
		(property "Tolerance" "1%"
			(at 276.86 252.73 0)
			(effects
				(font
					(size 1.27 1.27)
				)
				(justify left bottom)
				(hide yes)
			)
		)
		(pin "1"
		)
		(pin "2"
		)
		(instances
			(project "jetson-agx-thor-baseboard"
				(path ""
					(reference "R191")
					(unit 1)
				)
			)
		)
	)
	(symbol
		(lib_id "antmicroCapacitors0402:C_100n_0402")
		(at 287.02 95.25 0)
		(mirror x)
		(unit 1)
		(exclude_from_sim no)
		(in_bom yes)
		(on_board yes)
		(dnp no)
		(property "Reference" "C338"
			(at 295.656 93.98 0)
			(effects
				(font
					(size 1.27 1.27)
				)
				(justify right)
			)
		)
		(property "Value" "C_100n_0402"
			(at 307.34 85.09 0)
			(effects
				(font
					(size 1.27 1.27)
					(thickness 0.15)
				)
				(justify left bottom)
				(hide yes)
			)
		)
		(property "Footprint" "antmicro-footprints:C_0402_1005Metric"
			(at 307.34 82.55 0)
			(effects
				(font
					(size 1.27 1.27)
					(thickness 0.15)
				)
				(justify left bottom)
				(hide yes)
			)
		)
		(property "Datasheet" "https://www.murata.com/products/productdetail?partno=GRM155R61H104KE14%23"
			(at 307.34 80.01 0)
			(effects
				(font
					(size 1.27 1.27)
					(thickness 0.15)
				)
				(justify left bottom)
				(hide yes)
			)
		)
		(property "Description" "SMD Multilayer Ceramic Capacitor, 0.1 µF, 50 V, 0402 [1005 Metric], ± 10%, X5R, GRM Series"
			(at 287.02 95.25 0)
			(effects
				(font
					(size 1.27 1.27)
				)
				(hide yes)
			)
		)
		(property "Manufacturer" "Murata"
			(at 307.34 74.93 0)
			(effects
				(font
					(size 1.27 1.27)
					(thickness 0.15)
				)
				(justify left bottom)
				(hide yes)
			)
		)
		(property "MPN" "GRM155R61H104KE14D"
			(at 307.34 77.47 0)
			(effects
				(font
					(size 1.27 1.27)
					(thickness 0.15)
				)
				(justify left bottom)
				(hide yes)
			)
		)
		(property "Val" "100n"
			(at 288.544 94.234 0)
			(effects
				(font
					(size 1.27 1.27)
					(thickness 0.15)
				)
				(justify right)
			)
		)
		(property "License" "Apache-2.0"
			(at 307.34 72.39 0)
			(effects
				(font
					(size 1.27 1.27)
					(thickness 0.15)
				)
				(justify left bottom)
				(hide yes)
			)
		)
		(property "Author" "Antmicro"
			(at 307.34 69.85 0)
			(effects
				(font
					(size 1.27 1.27)
					(thickness 0.15)
				)
				(justify left bottom)
				(hide yes)
			)
		)
		(property "Voltage" "50V"
			(at 307.34 67.31 0)
			(effects
				(font
					(size 1.27 1.27)
				)
				(justify left bottom)
				(hide yes)
			)
		)
		(property "Dielectric" "X5R"
			(at 307.34 64.77 0)
			(effects
				(font
					(size 1.27 1.27)
				)
				(justify left bottom)
				(hide yes)
			)
		)
		(pin "1"
		)
		(pin "2"
		)
		(instances
			(project "jetson-agx-thor-baseboard"
				(path ""
					(reference "C338")
					(unit 1)
				)
			)
		)
	)
	(symbol
		(lib_id "antmicroB2BConnectors:Hermaphroditic_Molex_203456-0003_CUSTOM_Jetson_AGX_Thor_H8mm")
		(at 313.69 224.79 0)
		(unit 7)
		(exclude_from_sim no)
		(in_bom yes)
		(on_board yes)
		(dnp no)
		(fields_autoplaced yes)
		(property "Reference" "J1"
			(at 340.36 217.17 0)
			(effects
				(font
					(size 1.27 1.27)
				)
			)
		)
		(property "Value" "Hermaphroditic_Molex_203456-0003_CUSTOM_Jetson_AGX_Thor_H8mm"
			(at 390.144 230.886 0)
			(effects
				(font
					(size 1.27 1.27)
				)
				(justify left bottom)
				(hide yes)
			)
		)
		(property "Footprint" "antmicro-footprints:Conn_Hermaphroditic_Molex_203456-0003_mirrored"
			(at 390.144 233.172 0)
			(effects
				(font
					(size 1.27 1.27)
				)
				(justify left bottom)
				(hide yes)
			)
		)
		(property "Datasheet" "https://www.molex.com/content/dam/molex/molex-dot-com/products/automated/en-us/salesdrawingpdf/203/203456/2034560003_sd.pdf?inline"
			(at 390.144 235.458 0)
			(effects
				(font
					(size 1.27 1.27)
				)
				(justify left bottom)
				(hide yes)
			)
		)
		(property "Description" "Mirror Mezz Hermaphroditic Connector, 5.50mm Connector Height, BGA-Attach Mounting, 7 Pair, 11 Row, 699 Circuits, 0.76µm Gold Plating, without Pegs"
			(at 390.144 244.094 0)
			(effects
				(font
					(size 1.27 1.27)
				)
				(justify left bottom)
				(hide yes)
			)
		)
		(property "MPN" "203456-0003"
			(at 340.36 219.71 0)
			(effects
				(font
					(size 1.27 1.27)
				)
			)
		)
		(property "Manufacturer" "Molex"
			(at 390.144 237.744 0)
			(effects
				(font
					(size 1.27 1.27)
				)
				(justify left bottom)
				(hide yes)
			)
		)
		(property "Author" "Antmicro"
			(at 390.144 239.776 0)
			(effects
				(font
					(size 1.27 1.27)
				)
				(justify left bottom)
				(hide yes)
			)
		)
		(property "License" "Apache-2.0"
			(at 390.144 241.808 0)
			(effects
				(font
					(size 1.27 1.27)
				)
				(justify left bottom)
				(hide yes)
			)
		)
		(pin "J37"
		)
		(pin "D37"
		)
		(pin "C40"
		)
		(pin "J40"
		)
		(pin "C30"
		)
		(pin "D28"
		)
		(pin "F57"
		)
		(pin "F45"
		)
		(pin "B48"
		)
		(pin "F46"
		)
		(pin "C41"
		)
		(pin "D23"
		)
		(pin "G48"
		)
		(pin "C42"
		)
		(pin "J5"
		)
		(pin "E56"
		)
		(pin "D27"
		)
		(pin "C27"
		)
		(pin "E28"
		)
		(pin "D63"
		)
		(pin "A40"
		)
		(pin "J21"
		)
		(pin "L24"
		)
		(pin "L59"
		)
		(pin "B27"
		)
		(pin "D1"
		)
		(pin "C16"
		)
		(pin "H12"
		)
		(pin "H19"
		)
		(pin "F9"
		)
		(pin "A42"
		)
		(pin "A41"
		)
		(pin "B42"
		)
		(pin "E7"
		)
		(pin "B43"
		)
		(pin "L54"
		)
		(pin "A57"
		)
		(pin "J42"
		)
		(pin "B12"
		)
		(pin "F63"
		)
		(pin "J38"
		)
		(pin "J41"
		)
		(pin "L43"
		)
		(pin "D59"
		)
		(pin "J65"
		)
		(pin "H26"
		)
		(pin "G19"
		)
		(pin "G7"
		)
		(pin "D12"
		)
		(pin "F34"
		)
		(pin "G42"
		)
		(pin "G41"
		)
		(pin "H42"
		)
		(pin "E30"
		)
		(pin "L62"
		)
		(pin "L49"
		)
		(pin "H43"
		)
		(pin "F27"
		)
		(pin "G64"
		)
		(pin "J54"
		)
		(pin "F39"
		)
		(pin "E38"
		)
		(pin "D8"
		)
		(pin "H30"
		)
		(pin "B33"
		)
		(pin "G12"
		)
		(pin "E39"
		)
		(pin "E5"
		)
		(pin "E41"
		)
		(pin "E42"
		)
		(pin "H16"
		)
		(pin "F42"
		)
		(pin "F43"
		)
		(pin "L56"
		)
		(pin "F21"
		)
		(pin "B21"
		)
		(pin "F20"
		)
		(pin "C19"
		)
		(pin "L15"
		)
		(pin "F50"
		)
		(pin "F37"
		)
		(pin "J60"
		)
		(pin "E18"
		)
		(pin "E64"
		)
		(pin "E19"
		)
		(pin "B13"
		)
		(pin "D9"
		)
		(pin "K56"
		)
		(pin "D5"
		)
		(pin "A19"
		)
		(pin "D45"
		)
		(pin "L12"
		)
		(pin "C47"
		)
		(pin "E13"
		)
		(pin "E46"
		)
		(pin "C24"
		)
		(pin "H64"
		)
		(pin "A24"
		)
		(pin "F3"
		)
		(pin "L27"
		)
		(pin "H40"
		)
		(pin "C20"
		)
		(pin "G13"
		)
		(pin "K29"
		)
		(pin "H65"
		)
		(pin "A9"
		)
		(pin "A13"
		)
		(pin "A30"
		)
		(pin "B34"
		)
		(pin "E12"
		)
		(pin "C11"
		)
		(pin "E23"
		)
		(pin "D7"
		)
		(pin "D18"
		)
		(pin "F65"
		)
		(pin "D53"
		)
		(pin "H35"
		)
		(pin "A25"
		)
		(pin "C3"
		)
		(pin "J33"
		)
		(pin "H39"
		)
		(pin "B50"
		)
		(pin "A63"
		)
		(pin "G65"
		)
		(pin "B22"
		)
		(pin "B18"
		)
		(pin "E57"
		)
		(pin "D29"
		)
		(pin "D19"
		)
		(pin "F25"
		)
		(pin "F28"
		)
		(pin "L10"
		)
		(pin "C31"
		)
		(pin "G1"
		)
		(pin "E16"
		)
		(pin "E40"
		)
		(pin "E20"
		)
		(pin "D50"
		)
		(pin "D57"
		)
		(pin "F59"
		)
		(pin "J64"
		)
		(pin "D49"
		)
		(pin "E62"
		)
		(pin "E24"
		)
		(pin "J26"
		)
		(pin "K25"
		)
		(pin "G26"
		)
		(pin "H29"
		)
		(pin "B29"
		)
		(pin "B38"
		)
		(pin "C10"
		)
		(pin "F12"
		)
		(pin "A46"
		)
		(pin "K12"
		)
		(pin "E17"
		)
		(pin "F16"
		)
		(pin "H25"
		)
		(pin "K16"
		)
		(pin "J30"
		)
		(pin "D17"
		)
		(pin "K37"
		)
		(pin "B5"
		)
		(pin "E50"
		)
		(pin "D16"
		)
		(pin "D4"
		)
		(pin "G40"
		)
		(pin "H7"
		)
		(pin "A45"
		)
		(pin "H45"
		)
		(pin "C18"
		)
		(pin "G36"
		)
		(pin "B58"
		)
		(pin "A10"
		)
		(pin "L52"
		)
		(pin "G54"
		)
		(pin "G53"
		)
		(pin "D20"
		)
		(pin "K50"
		)
		(pin "H61"
		)
		(pin "C54"
		)
		(pin "H33"
		)
		(pin "H51"
		)
		(pin "H62"
		)
		(pin "F44"
		)
		(pin "H32"
		)
		(pin "C6"
		)
		(pin "L25"
		)
		(pin "A35"
		)
		(pin "D55"
		)
		(pin "L9"
		)
		(pin "F41"
		)
		(pin "A56"
		)
		(pin "J18"
		)
		(pin "K7"
		)
		(pin "D13"
		)
		(pin "A34"
		)
		(pin "G33"
		)
		(pin "A38"
		)
		(pin "D24"
		)
		(pin "H63"
		)
		(pin "C58"
		)
		(pin "J35"
		)
		(pin "J51"
		)
		(pin "E61"
		)
		(pin "E25"
		)
		(pin "E29"
		)
		(pin "E63"
		)
		(pin "L60"
		)
		(pin "D62"
		)
		(pin "G58"
		)
		(pin "J12"
		)
		(pin "J59"
		)
		(pin "H15"
		)
		(pin "K36"
		)
		(pin "J24"
		)
		(pin "A54"
		)
		(pin "D32"
		)
		(pin "F62"
		)
		(pin "B54"
		)
		(pin "D33"
		)
		(pin "G14"
		)
		(pin "A22"
		)
		(pin "C14"
		)
		(pin "L3"
		)
		(pin "E2"
		)
		(pin "B11"
		)
		(pin "C23"
		)
		(pin "A12"
		)
		(pin "G15"
		)
		(pin "C15"
		)
		(pin "A59"
		)
		(pin "J15"
		)
		(pin "J57"
		)
		(pin "C7"
		)
		(pin "J14"
		)
		(pin "G59"
		)
		(pin "G39"
		)
		(pin "E54"
		)
		(pin "A37"
		)
		(pin "L41"
		)
		(pin "A14"
		)
		(pin "A15"
		)
		(pin "L51"
		)
		(pin "K47"
		)
		(pin "L46"
		)
		(pin "G4"
		)
		(pin "B15"
		)
		(pin "C34"
		)
		(pin "K46"
		)
		(pin "H37"
		)
		(pin "J48"
		)
		(pin "J47"
		)
		(pin "B9"
		)
		(pin "F49"
		)
		(pin "C22"
		)
		(pin "J39"
		)
		(pin "J13"
		)
		(pin "G50"
		)
		(pin "L6"
		)
		(pin "G51"
		)
		(pin "L8"
		)
		(pin "H9"
		)
		(pin "B56"
		)
		(pin "L53"
		)
		(pin "C12"
		)
		(pin "E59"
		)
		(pin "K24"
		)
		(pin "E52"
		)
		(pin "A27"
		)
		(pin "A31"
		)
		(pin "E21"
		)
		(pin "K17"
		)
		(pin "H49"
		)
		(pin "E22"
		)
		(pin "H21"
		)
		(pin "J63"
		)
		(pin "K28"
		)
		(pin "B28"
		)
		(pin "E65"
		)
		(pin "G52"
		)
		(pin "D44"
		)
		(pin "D47"
		)
		(pin "B4"
		)
		(pin "F2"
		)
		(pin "L35"
		)
		(pin "C52"
		)
		(pin "L42"
		)
		(pin "E32"
		)
		(pin "E37"
		)
		(pin "E33"
		)
		(pin "E43"
		)
		(pin "E15"
		)
		(pin "G30"
		)
		(pin "D41"
		)
		(pin "J31"
		)
		(pin "E9"
		)
		(pin "F14"
		)
		(pin "L5"
		)
		(pin "E3"
		)
		(pin "L34"
		)
		(pin "C25"
		)
		(pin "J4"
		)
		(pin "K42"
		)
		(pin "G63"
		)
		(pin "A16"
		)
		(pin "L30"
		)
		(pin "E1"
		)
		(pin "A36"
		)
		(pin "L20"
		)
		(pin "J2"
		)
		(pin "K45"
		)
		(pin "A3"
		)
		(pin "L23"
		)
		(pin "A33"
		)
		(pin "A17"
		)
		(pin "H41"
		)
		(pin "C46"
		)
		(pin "L31"
		)
		(pin "H44"
		)
		(pin "F64"
		)
		(pin "A28"
		)
		(pin "C21"
		)
		(pin "F1"
		)
		(pin "A20"
		)
		(pin "B53"
		)
		(pin "A29"
		)
		(pin "E49"
		)
		(pin "G27"
		)
		(pin "E14"
		)
		(pin "H4"
		)
		(pin "H13"
		)
		(pin "F32"
		)
		(pin "F13"
		)
		(pin "E36"
		)
		(pin "D39"
		)
		(pin "H48"
		)
		(pin "K43"
		)
		(pin "F40"
		)
		(pin "G57"
		)
		(pin "C4"
		)
		(pin "K53"
		)
		(pin "D40"
		)
		(pin "H46"
		)
		(pin "H10"
		)
		(pin "C56"
		)
		(pin "L21"
		)
		(pin "G6"
		)
		(pin "H28"
		)
		(pin "K13"
		)
		(pin "L47"
		)
		(pin "C48"
		)
		(pin "D10"
		)
		(pin "D43"
		)
		(pin "A44"
		)
		(pin "D46"
		)
		(pin "C45"
		)
		(pin "J9"
		)
		(pin "C50"
		)
		(pin "L16"
		)
		(pin "B46"
		)
		(pin "E47"
		)
		(pin "H36"
		)
		(pin "B45"
		)
		(pin "C44"
		)
		(pin "L18"
		)
		(pin "D42"
		)
		(pin "A8"
		)
		(pin "C38"
		)
		(pin "E48"
		)
		(pin "K49"
		)
		(pin "L50"
		)
		(pin "K54"
		)
		(pin "J29"
		)
		(pin "K48"
		)
		(pin "C61"
		)
		(pin "D21"
		)
		(pin "K5"
		)
		(pin "C51"
		)
		(pin "H53"
		)
		(pin "J7"
		)
		(pin "A50"
		)
		(pin "H56"
		)
		(pin "A51"
		)
		(pin "H47"
		)
		(pin "H18"
		)
		(pin "G47"
		)
		(pin "D6"
		)
		(pin "B51"
		)
		(pin "G5"
		)
		(pin "B52"
		)
		(pin "H22"
		)
		(pin "L14"
		)
		(pin "D52"
		)
		(pin "E31"
		)
		(pin "J53"
		)
		(pin "B61"
		)
		(pin "G20"
		)
		(pin "B60"
		)
		(pin "L29"
		)
		(pin "F31"
		)
		(pin "G60"
		)
		(pin "F60"
		)
		(pin "D51"
		)
		(pin "F56"
		)
		(pin "G38"
		)
		(pin "J50"
		)
		(pin "L45"
		)
		(pin "J43"
		)
		(pin "F8"
		)
		(pin "J34"
		)
		(pin "E51"
		)
		(pin "A43"
		)
		(pin "F36"
		)
		(pin "B30"
		)
		(pin "B32"
		)
		(pin "L44"
		)
		(pin "K62"
		)
		(pin "D2"
		)
		(pin "L57"
		)
		(pin "E45"
		)
		(pin "H55"
		)
		(pin "A47"
		)
		(pin "H1"
		)
		(pin "C29"
		)
		(pin "B6"
		)
		(pin "B20"
		)
		(pin "C33"
		)
		(pin "J55"
		)
		(pin "C64"
		)
		(pin "F47"
		)
		(pin "A55"
		)
		(pin "D60"
		)
		(pin "J52"
		)
		(pin "F51"
		)
		(pin "H5"
		)
		(pin "C28"
		)
		(pin "F7"
		)
		(pin "A48"
		)
		(pin "H59"
		)
		(pin "K6"
		)
		(pin "D36"
		)
		(pin "F6"
		)
		(pin "F52"
		)
		(pin "J49"
		)
		(pin "J19"
		)
		(pin "C5"
		)
		(pin "G56"
		)
		(pin "H17"
		)
		(pin "E58"
		)
		(pin "E27"
		)
		(pin "F38"
		)
		(pin "H6"
		)
		(pin "G21"
		)
		(pin "D26"
		)
		(pin "J11"
		)
		(pin "B16"
		)
		(pin "B59"
		)
		(pin "A5"
		)
		(pin "K58"
		)
		(pin "L48"
		)
		(pin "A58"
		)
		(pin "F61"
		)
		(pin "K15"
		)
		(pin "G23"
		)
		(pin "E4"
		)
		(pin "H31"
		)
		(pin "K10"
		)
		(pin "D65"
		)
		(pin "G34"
		)
		(pin "L38"
		)
		(pin "K33"
		)
		(pin "C43"
		)
		(pin "F18"
		)
		(pin "E35"
		)
		(pin "D48"
		)
		(pin "G18"
		)
		(pin "K9"
		)
		(pin "C53"
		)
		(pin "E6"
		)
		(pin "C55"
		)
		(pin "J8"
		)
		(pin "D35"
		)
		(pin "F48"
		)
		(pin "E44"
		)
		(pin "B55"
		)
		(pin "E34"
		)
		(pin "G11"
		)
		(pin "G61"
		)
		(pin "K51"
		)
		(pin "K20"
		)
		(pin "A49"
		)
		(pin "H23"
		)
		(pin "C62"
		)
		(pin "B24"
		)
		(pin "G2"
		)
		(pin "B14"
		)
		(pin "G22"
		)
		(pin "A60"
		)
		(pin "K27"
		)
		(pin "H54"
		)
		(pin "B7"
		)
		(pin "A61"
		)
		(pin "D56"
		)
		(pin "G32"
		)
		(pin "B26"
		)
		(pin "B44"
		)
		(pin "H38"
		)
		(pin "C49"
		)
		(pin "D15"
		)
		(pin "B49"
		)
		(pin "B17"
		)
		(pin "F35"
		)
		(pin "B39"
		)
		(pin "F5"
		)
		(pin "J3"
		)
		(pin "J46"
		)
		(pin "J28"
		)
		(pin "J36"
		)
		(pin "J25"
		)
		(pin "J32"
		)
		(pin "L22"
		)
		(pin "K22"
		)
		(pin "J20"
		)
		(pin "C32"
		)
		(pin "F10"
		)
		(pin "G16"
		)
		(pin "F55"
		)
		(pin "K40"
		)
		(pin "H20"
		)
		(pin "K32"
		)
		(pin "G3"
		)
		(pin "A32"
		)
		(pin "J10"
		)
		(pin "C13"
		)
		(pin "L55"
		)
		(pin "G46"
		)
		(pin "G35"
		)
		(pin "L26"
		)
		(pin "E60"
		)
		(pin "J23"
		)
		(pin "J22"
		)
		(pin "A21"
		)
		(pin "L39"
		)
		(pin "C36"
		)
		(pin "L36"
		)
		(pin "G17"
		)
		(pin "J58"
		)
		(pin "K52"
		)
		(pin "B25"
		)
		(pin "E11"
		)
		(pin "B36"
		)
		(pin "A52"
		)
		(pin "B35"
		)
		(pin "D3"
		)
		(pin "K21"
		)
		(pin "E26"
		)
		(pin "F23"
		)
		(pin "F26"
		)
		(pin "G9"
		)
		(pin "D61"
		)
		(pin "C37"
		)
		(pin "K23"
		)
		(pin "G28"
		)
		(pin "H34"
		)
		(pin "D30"
		)
		(pin "H50"
		)
		(pin "G49"
		)
		(pin "B47"
		)
		(pin "B31"
		)
		(pin "A18"
		)
		(pin "J17"
		)
		(pin "C8"
		)
		(pin "C26"
		)
		(pin "G29"
		)
		(pin "E53"
		)
		(pin "G8"
		)
		(pin "K34"
		)
		(pin "K31"
		)
		(pin "G31"
		)
		(pin "K59"
		)
		(pin "L61"
		)
		(pin "C9"
		)
		(pin "D14"
		)
		(pin "K39"
		)
		(pin "C60"
		)
		(pin "F17"
		)
		(pin "B10"
		)
		(pin "L33"
		)
		(pin "H11"
		)
		(pin "L13"
		)
		(pin "D31"
		)
		(pin "F33"
		)
		(pin "A39"
		)
		(pin "A6"
		)
		(pin "C57"
		)
		(pin "H8"
		)
		(pin "G24"
		)
		(pin "B19"
		)
		(pin "F53"
		)
		(pin "K38"
		)
		(pin "A23"
		)
		(pin "C59"
		)
		(pin "J56"
		)
		(pin "D54"
		)
		(pin "F4"
		)
		(pin "A4"
		)
		(pin "F15"
		)
		(pin "G55"
		)
		(pin "E55"
		)
		(pin "J45"
		)
		(pin "D58"
		)
		(pin "J44"
		)
		(pin "K41"
		)
		(pin "A11"
		)
		(pin "G62"
		)
		(pin "J6"
		)
		(pin "H2"
		)
		(pin "L7"
		)
		(pin "C35"
		)
		(pin "L4"
		)
		(pin "E10"
		)
		(pin "A7"
		)
		(pin "L28"
		)
		(pin "K3"
		)
		(pin "J1"
		)
		(pin "K61"
		)
		(pin "G37"
		)
		(pin "L58"
		)
		(pin "A53"
		)
		(pin "L40"
		)
		(pin "F22"
		)
		(pin "K18"
		)
		(pin "D38"
		)
		(pin "K11"
		)
		(pin "H58"
		)
		(pin "A62"
		)
		(pin "K35"
		)
		(pin "D64"
		)
		(pin "G44"
		)
		(pin "H52"
		)
		(pin "H14"
		)
		(pin "K44"
		)
		(pin "F30"
		)
		(pin "D11"
		)
		(pin "C39"
		)
		(pin "K8"
		)
		(pin "F29"
		)
		(pin "F58"
		)
		(pin "B8"
		)
		(pin "B57"
		)
		(pin "B23"
		)
		(pin "G10"
		)
		(pin "K55"
		)
		(pin "G25"
		)
		(pin "L37"
		)
		(pin "H27"
		)
		(pin "H3"
		)
		(pin "F54"
		)
		(pin "K19"
		)
		(pin "G45"
		)
		(pin "L11"
		)
		(pin "J16"
		)
		(pin "K60"
		)
		(pin "B40"
		)
		(pin "J62"
		)
		(pin "K63"
		)
		(pin "H57"
		)
		(pin "L19"
		)
		(pin "L17"
		)
		(pin "C63"
		)
		(pin "E8"
		)
		(pin "D25"
		)
		(pin "C1"
		)
		(pin "C2"
		)
		(pin "B3"
		)
		(pin "B63"
		)
		(pin "C65"
		)
		(pin "K26"
		)
		(pin "A26"
		)
		(pin "G43"
		)
		(pin "H60"
		)
		(pin "F24"
		)
		(pin "H24"
		)
		(pin "J27"
		)
		(pin "C17"
		)
		(pin "F11"
		)
		(pin "F19"
		)
		(pin "J61"
		)
		(pin "K14"
		)
		(pin "K57"
		)
		(pin "L32"
		)
		(pin "B62"
		)
		(pin "D22"
		)
		(pin "D34"
		)
		(pin "L63"
		)
		(pin "B41"
		)
		(pin "K30"
		)
		(pin "B37"
		)
		(pin "K4"
		)
		(instances
			(project ""
				(path ""
					(reference "J1")
					(unit 7)
				)
			)
		)
	)
	(symbol
		(lib_id "antmicroResistors0402:R_33R_0402")
		(at 257.81 265.43 0)
		(unit 1)
		(exclude_from_sim no)
		(in_bom yes)
		(on_board yes)
		(dnp no)
		(property "Reference" "R190"
			(at 255.27 264.16 0)
			(effects
				(font
					(size 1.27 1.27)
					(thickness 0.15)
				)
			)
		)
		(property "Value" "R_33R_0402"
			(at 278.13 278.13 0)
			(effects
				(font
					(size 1.27 1.27)
					(thickness 0.15)
				)
				(justify left bottom)
				(hide yes)
			)
		)
		(property "Footprint" "antmicro-footprints:R_0402_1005Metric"
			(at 278.13 280.67 0)
			(effects
				(font
					(size 1.27 1.27)
					(thickness 0.15)
				)
				(justify left bottom)
				(hide yes)
			)
		)
		(property "Datasheet" "https://www.bourns.com/docs/product-datasheets/cr.pdf"
			(at 278.13 283.21 0)
			(effects
				(font
					(size 1.27 1.27)
					(thickness 0.15)
				)
				(justify left bottom)
				(hide yes)
			)
		)
		(property "Description" "SMD Chip Resistor, 33 ohm, ± 1%, 62.5 mW, 0402 [1005 Metric], Thick Film, General Purpose"
			(at 257.81 265.43 0)
			(effects
				(font
					(size 1.27 1.27)
				)
				(hide yes)
			)
		)
		(property "MPN" "CR0402-FX-33R0GLF"
			(at 278.13 285.75 0)
			(effects
				(font
					(size 1.27 1.27)
					(thickness 0.15)
				)
				(justify left bottom)
				(hide yes)
			)
		)
		(property "Manufacturer" "Bourns"
			(at 278.13 288.29 0)
			(effects
				(font
					(size 1.27 1.27)
					(thickness 0.15)
				)
				(justify left bottom)
				(hide yes)
			)
		)
		(property "License" "Apache-2.0"
			(at 278.13 290.83 0)
			(effects
				(font
					(size 1.27 1.27)
					(thickness 0.15)
				)
				(justify left bottom)
				(hide yes)
			)
		)
		(property "Author" "Antmicro"
			(at 278.13 293.37 0)
			(effects
				(font
					(size 1.27 1.27)
					(thickness 0.15)
				)
				(justify left bottom)
				(hide yes)
			)
		)
		(property "Val" "33R"
			(at 264.795 264.16 0)
			(effects
				(font
					(size 1.27 1.27)
					(thickness 0.15)
				)
			)
		)
		(property "Tolerance" "1%"
			(at 278.13 275.59 0)
			(effects
				(font
					(size 1.27 1.27)
				)
				(justify left bottom)
				(hide yes)
			)
		)
		(pin "2"
		)
		(pin "1"
		)
		(instances
			(project "jetson-agx-thor-baseboard"
				(path ""
					(reference "R190")
					(unit 1)
				)
			)
		)
	)
	(symbol
		(lib_id "antmicroTransistorsFETsMOSFETsSingle:DMG1012T-7")
		(at 123.19 271.78 0)
		(mirror y)
		(unit 1)
		(exclude_from_sim no)
		(in_bom no)
		(on_board yes)
		(dnp yes)
		(fields_autoplaced yes)
		(property "Reference" "Q28"
			(at 113.03 267.97 0)
			(effects
				(font
					(size 1.27 1.27)
					(thickness 0.15)
				)
				(justify left)
			)
		)
		(property "Value" "DMG1012T-7"
			(at 100.33 280.67 0)
			(effects
				(font
					(size 1.27 1.27)
					(thickness 0.15)
				)
				(justify left bottom)
				(hide yes)
			)
		)
		(property "Footprint" "antmicro-footprints:SOT-523"
			(at 100.33 283.21 0)
			(effects
				(font
					(size 1.27 1.27)
					(thickness 0.15)
				)
				(justify left bottom)
				(hide yes)
			)
		)
		(property "Datasheet" "https://www.diodes.com/assets/Datasheets/ds31783.pdf"
			(at 100.33 285.75 0)
			(effects
				(font
					(size 1.27 1.27)
					(thickness 0.15)
				)
				(justify left bottom)
				(hide yes)
			)
		)
		(property "Description" "Power MOSFET, N Channel, 20 V, 630 mA, 0.3 ohm, SOT-523, Surface Mount"
			(at 100.33 297.434 0)
			(effects
				(font
					(size 1.27 1.27)
				)
				(justify left)
				(hide yes)
			)
		)
		(property "MPN" "DMG1012T-7"
			(at 113.03 270.51 0)
			(effects
				(font
					(size 1.27 1.27)
					(thickness 0.15)
				)
				(justify left)
			)
		)
		(property "Manufacturer" "Diodes Incorporated"
			(at 100.33 290.83 0)
			(effects
				(font
					(size 1.27 1.27)
					(thickness 0.15)
				)
				(justify left bottom)
				(hide yes)
			)
		)
		(property "Author" "Antmicro"
			(at 100.33 293.37 0)
			(effects
				(font
					(size 1.27 1.27)
					(thickness 0.15)
				)
				(justify left bottom)
				(hide yes)
			)
		)
		(property "License" "Apache-2.0"
			(at 100.33 295.91 0)
			(effects
				(font
					(size 1.27 1.27)
					(thickness 0.15)
				)
				(justify left bottom)
				(hide yes)
			)
		)
		(pin "2"
		)
		(pin "1"
		)
		(pin "3"
		)
		(instances
			(project "jetson-agx-thor-baseboard"
				(path ""
					(reference "Q28")
					(unit 1)
				)
			)
		)
	)
	(symbol
		(lib_id "antmicroB2BConnectors:Hermaphroditic_Molex_203456-0003_CUSTOM_Jetson_AGX_Thor_H8mm")
		(at 321.31 149.86 0)
		(unit 6)
		(exclude_from_sim no)
		(in_bom yes)
		(on_board yes)
		(dnp no)
		(fields_autoplaced yes)
		(property "Reference" "J1"
			(at 339.725 142.24 0)
			(effects
				(font
					(size 1.27 1.27)
				)
			)
		)
		(property "Value" "Hermaphroditic_Molex_203456-0003_CUSTOM_Jetson_AGX_Thor_H8mm"
			(at 397.764 155.956 0)
			(effects
				(font
					(size 1.27 1.27)
				)
				(justify left bottom)
				(hide yes)
			)
		)
		(property "Footprint" "antmicro-footprints:Conn_Hermaphroditic_Molex_203456-0003_mirrored"
			(at 397.764 158.242 0)
			(effects
				(font
					(size 1.27 1.27)
				)
				(justify left bottom)
				(hide yes)
			)
		)
		(property "Datasheet" "https://www.molex.com/content/dam/molex/molex-dot-com/products/automated/en-us/salesdrawingpdf/203/203456/2034560003_sd.pdf?inline"
			(at 397.764 160.528 0)
			(effects
				(font
					(size 1.27 1.27)
				)
				(justify left bottom)
				(hide yes)
			)
		)
		(property "Description" "Mirror Mezz Hermaphroditic Connector, 5.50mm Connector Height, BGA-Attach Mounting, 7 Pair, 11 Row, 699 Circuits, 0.76µm Gold Plating, without Pegs"
			(at 397.764 169.164 0)
			(effects
				(font
					(size 1.27 1.27)
				)
				(justify left bottom)
				(hide yes)
			)
		)
		(property "MPN" "203456-0003"
			(at 339.725 144.78 0)
			(effects
				(font
					(size 1.27 1.27)
				)
			)
		)
		(property "Manufacturer" "Molex"
			(at 397.764 162.814 0)
			(effects
				(font
					(size 1.27 1.27)
				)
				(justify left bottom)
				(hide yes)
			)
		)
		(property "Author" "Antmicro"
			(at 397.764 164.846 0)
			(effects
				(font
					(size 1.27 1.27)
				)
				(justify left bottom)
				(hide yes)
			)
		)
		(property "License" "Apache-2.0"
			(at 397.764 166.878 0)
			(effects
				(font
					(size 1.27 1.27)
				)
				(justify left bottom)
				(hide yes)
			)
		)
		(pin "J37"
		)
		(pin "D37"
		)
		(pin "C40"
		)
		(pin "J40"
		)
		(pin "C30"
		)
		(pin "D28"
		)
		(pin "F57"
		)
		(pin "F45"
		)
		(pin "B48"
		)
		(pin "F46"
		)
		(pin "C41"
		)
		(pin "D23"
		)
		(pin "G48"
		)
		(pin "C42"
		)
		(pin "J5"
		)
		(pin "E56"
		)
		(pin "D27"
		)
		(pin "C27"
		)
		(pin "E28"
		)
		(pin "D63"
		)
		(pin "A40"
		)
		(pin "J21"
		)
		(pin "L24"
		)
		(pin "L59"
		)
		(pin "B27"
		)
		(pin "D1"
		)
		(pin "C16"
		)
		(pin "H12"
		)
		(pin "H19"
		)
		(pin "F9"
		)
		(pin "A42"
		)
		(pin "A41"
		)
		(pin "B42"
		)
		(pin "E7"
		)
		(pin "B43"
		)
		(pin "L54"
		)
		(pin "A57"
		)
		(pin "J42"
		)
		(pin "B12"
		)
		(pin "F63"
		)
		(pin "J38"
		)
		(pin "J41"
		)
		(pin "L43"
		)
		(pin "D59"
		)
		(pin "J65"
		)
		(pin "H26"
		)
		(pin "G19"
		)
		(pin "G7"
		)
		(pin "D12"
		)
		(pin "F34"
		)
		(pin "G42"
		)
		(pin "G41"
		)
		(pin "H42"
		)
		(pin "E30"
		)
		(pin "L62"
		)
		(pin "L49"
		)
		(pin "H43"
		)
		(pin "F27"
		)
		(pin "G64"
		)
		(pin "J54"
		)
		(pin "F39"
		)
		(pin "E38"
		)
		(pin "D8"
		)
		(pin "H30"
		)
		(pin "B33"
		)
		(pin "G12"
		)
		(pin "E39"
		)
		(pin "E5"
		)
		(pin "E41"
		)
		(pin "E42"
		)
		(pin "H16"
		)
		(pin "F42"
		)
		(pin "F43"
		)
		(pin "L56"
		)
		(pin "F21"
		)
		(pin "B21"
		)
		(pin "F20"
		)
		(pin "C19"
		)
		(pin "L15"
		)
		(pin "F50"
		)
		(pin "F37"
		)
		(pin "J60"
		)
		(pin "E18"
		)
		(pin "E64"
		)
		(pin "E19"
		)
		(pin "B13"
		)
		(pin "D9"
		)
		(pin "K56"
		)
		(pin "D5"
		)
		(pin "A19"
		)
		(pin "D45"
		)
		(pin "L12"
		)
		(pin "C47"
		)
		(pin "E13"
		)
		(pin "E46"
		)
		(pin "C24"
		)
		(pin "H64"
		)
		(pin "A24"
		)
		(pin "F3"
		)
		(pin "L27"
		)
		(pin "H40"
		)
		(pin "C20"
		)
		(pin "G13"
		)
		(pin "K29"
		)
		(pin "H65"
		)
		(pin "A9"
		)
		(pin "A13"
		)
		(pin "A30"
		)
		(pin "B34"
		)
		(pin "E12"
		)
		(pin "C11"
		)
		(pin "E23"
		)
		(pin "D7"
		)
		(pin "D18"
		)
		(pin "F65"
		)
		(pin "D53"
		)
		(pin "H35"
		)
		(pin "A25"
		)
		(pin "C3"
		)
		(pin "J33"
		)
		(pin "H39"
		)
		(pin "B50"
		)
		(pin "A63"
		)
		(pin "G65"
		)
		(pin "B22"
		)
		(pin "B18"
		)
		(pin "E57"
		)
		(pin "D29"
		)
		(pin "D19"
		)
		(pin "F25"
		)
		(pin "F28"
		)
		(pin "L10"
		)
		(pin "C31"
		)
		(pin "G1"
		)
		(pin "E16"
		)
		(pin "E40"
		)
		(pin "E20"
		)
		(pin "D50"
		)
		(pin "D57"
		)
		(pin "F59"
		)
		(pin "J64"
		)
		(pin "D49"
		)
		(pin "E62"
		)
		(pin "E24"
		)
		(pin "J26"
		)
		(pin "K25"
		)
		(pin "G26"
		)
		(pin "H29"
		)
		(pin "B29"
		)
		(pin "B38"
		)
		(pin "C10"
		)
		(pin "F12"
		)
		(pin "A46"
		)
		(pin "K12"
		)
		(pin "E17"
		)
		(pin "F16"
		)
		(pin "H25"
		)
		(pin "K16"
		)
		(pin "J30"
		)
		(pin "D17"
		)
		(pin "K37"
		)
		(pin "B5"
		)
		(pin "E50"
		)
		(pin "D16"
		)
		(pin "D4"
		)
		(pin "G40"
		)
		(pin "H7"
		)
		(pin "A45"
		)
		(pin "H45"
		)
		(pin "C18"
		)
		(pin "G36"
		)
		(pin "B58"
		)
		(pin "A10"
		)
		(pin "L52"
		)
		(pin "G54"
		)
		(pin "G53"
		)
		(pin "D20"
		)
		(pin "K50"
		)
		(pin "H61"
		)
		(pin "C54"
		)
		(pin "H33"
		)
		(pin "H51"
		)
		(pin "H62"
		)
		(pin "F44"
		)
		(pin "H32"
		)
		(pin "C6"
		)
		(pin "L25"
		)
		(pin "A35"
		)
		(pin "D55"
		)
		(pin "L9"
		)
		(pin "F41"
		)
		(pin "A56"
		)
		(pin "J18"
		)
		(pin "K7"
		)
		(pin "D13"
		)
		(pin "A34"
		)
		(pin "G33"
		)
		(pin "A38"
		)
		(pin "D24"
		)
		(pin "H63"
		)
		(pin "C58"
		)
		(pin "J35"
		)
		(pin "J51"
		)
		(pin "E61"
		)
		(pin "E25"
		)
		(pin "E29"
		)
		(pin "E63"
		)
		(pin "L60"
		)
		(pin "D62"
		)
		(pin "G58"
		)
		(pin "J12"
		)
		(pin "J59"
		)
		(pin "H15"
		)
		(pin "K36"
		)
		(pin "J24"
		)
		(pin "A54"
		)
		(pin "D32"
		)
		(pin "F62"
		)
		(pin "B54"
		)
		(pin "D33"
		)
		(pin "G14"
		)
		(pin "A22"
		)
		(pin "C14"
		)
		(pin "L3"
		)
		(pin "E2"
		)
		(pin "B11"
		)
		(pin "C23"
		)
		(pin "A12"
		)
		(pin "G15"
		)
		(pin "C15"
		)
		(pin "A59"
		)
		(pin "J15"
		)
		(pin "J57"
		)
		(pin "C7"
		)
		(pin "J14"
		)
		(pin "G59"
		)
		(pin "G39"
		)
		(pin "E54"
		)
		(pin "A37"
		)
		(pin "L41"
		)
		(pin "A14"
		)
		(pin "A15"
		)
		(pin "L51"
		)
		(pin "K47"
		)
		(pin "L46"
		)
		(pin "G4"
		)
		(pin "B15"
		)
		(pin "C34"
		)
		(pin "K46"
		)
		(pin "H37"
		)
		(pin "J48"
		)
		(pin "J47"
		)
		(pin "B9"
		)
		(pin "F49"
		)
		(pin "C22"
		)
		(pin "J39"
		)
		(pin "J13"
		)
		(pin "G50"
		)
		(pin "L6"
		)
		(pin "G51"
		)
		(pin "L8"
		)
		(pin "H9"
		)
		(pin "B56"
		)
		(pin "L53"
		)
		(pin "C12"
		)
		(pin "E59"
		)
		(pin "K24"
		)
		(pin "E52"
		)
		(pin "A27"
		)
		(pin "A31"
		)
		(pin "E21"
		)
		(pin "K17"
		)
		(pin "H49"
		)
		(pin "E22"
		)
		(pin "H21"
		)
		(pin "J63"
		)
		(pin "K28"
		)
		(pin "B28"
		)
		(pin "E65"
		)
		(pin "G52"
		)
		(pin "D44"
		)
		(pin "D47"
		)
		(pin "B4"
		)
		(pin "F2"
		)
		(pin "L35"
		)
		(pin "C52"
		)
		(pin "L42"
		)
		(pin "E32"
		)
		(pin "E37"
		)
		(pin "E33"
		)
		(pin "E43"
		)
		(pin "E15"
		)
		(pin "G30"
		)
		(pin "D41"
		)
		(pin "J31"
		)
		(pin "E9"
		)
		(pin "F14"
		)
		(pin "L5"
		)
		(pin "E3"
		)
		(pin "L34"
		)
		(pin "C25"
		)
		(pin "J4"
		)
		(pin "K42"
		)
		(pin "G63"
		)
		(pin "A16"
		)
		(pin "L30"
		)
		(pin "E1"
		)
		(pin "A36"
		)
		(pin "L20"
		)
		(pin "J2"
		)
		(pin "K45"
		)
		(pin "A3"
		)
		(pin "L23"
		)
		(pin "A33"
		)
		(pin "A17"
		)
		(pin "H41"
		)
		(pin "C46"
		)
		(pin "L31"
		)
		(pin "H44"
		)
		(pin "F64"
		)
		(pin "A28"
		)
		(pin "C21"
		)
		(pin "F1"
		)
		(pin "A20"
		)
		(pin "B53"
		)
		(pin "A29"
		)
		(pin "E49"
		)
		(pin "G27"
		)
		(pin "E14"
		)
		(pin "H4"
		)
		(pin "H13"
		)
		(pin "F32"
		)
		(pin "F13"
		)
		(pin "E36"
		)
		(pin "D39"
		)
		(pin "H48"
		)
		(pin "K43"
		)
		(pin "F40"
		)
		(pin "G57"
		)
		(pin "C4"
		)
		(pin "K53"
		)
		(pin "D40"
		)
		(pin "H46"
		)
		(pin "H10"
		)
		(pin "C56"
		)
		(pin "L21"
		)
		(pin "G6"
		)
		(pin "H28"
		)
		(pin "K13"
		)
		(pin "L47"
		)
		(pin "C48"
		)
		(pin "D10"
		)
		(pin "D43"
		)
		(pin "A44"
		)
		(pin "D46"
		)
		(pin "C45"
		)
		(pin "J9"
		)
		(pin "C50"
		)
		(pin "L16"
		)
		(pin "B46"
		)
		(pin "E47"
		)
		(pin "H36"
		)
		(pin "B45"
		)
		(pin "C44"
		)
		(pin "L18"
		)
		(pin "D42"
		)
		(pin "A8"
		)
		(pin "C38"
		)
		(pin "E48"
		)
		(pin "K49"
		)
		(pin "L50"
		)
		(pin "K54"
		)
		(pin "J29"
		)
		(pin "K48"
		)
		(pin "C61"
		)
		(pin "D21"
		)
		(pin "K5"
		)
		(pin "C51"
		)
		(pin "H53"
		)
		(pin "J7"
		)
		(pin "A50"
		)
		(pin "H56"
		)
		(pin "A51"
		)
		(pin "H47"
		)
		(pin "H18"
		)
		(pin "G47"
		)
		(pin "D6"
		)
		(pin "B51"
		)
		(pin "G5"
		)
		(pin "B52"
		)
		(pin "H22"
		)
		(pin "L14"
		)
		(pin "D52"
		)
		(pin "E31"
		)
		(pin "J53"
		)
		(pin "B61"
		)
		(pin "G20"
		)
		(pin "B60"
		)
		(pin "L29"
		)
		(pin "F31"
		)
		(pin "G60"
		)
		(pin "F60"
		)
		(pin "D51"
		)
		(pin "F56"
		)
		(pin "G38"
		)
		(pin "J50"
		)
		(pin "L45"
		)
		(pin "J43"
		)
		(pin "F8"
		)
		(pin "J34"
		)
		(pin "E51"
		)
		(pin "A43"
		)
		(pin "F36"
		)
		(pin "B30"
		)
		(pin "B32"
		)
		(pin "L44"
		)
		(pin "K62"
		)
		(pin "D2"
		)
		(pin "L57"
		)
		(pin "E45"
		)
		(pin "H55"
		)
		(pin "A47"
		)
		(pin "H1"
		)
		(pin "C29"
		)
		(pin "B6"
		)
		(pin "B20"
		)
		(pin "C33"
		)
		(pin "J55"
		)
		(pin "C64"
		)
		(pin "F47"
		)
		(pin "A55"
		)
		(pin "D60"
		)
		(pin "J52"
		)
		(pin "F51"
		)
		(pin "H5"
		)
		(pin "C28"
		)
		(pin "F7"
		)
		(pin "A48"
		)
		(pin "H59"
		)
		(pin "K6"
		)
		(pin "D36"
		)
		(pin "F6"
		)
		(pin "F52"
		)
		(pin "J49"
		)
		(pin "J19"
		)
		(pin "C5"
		)
		(pin "G56"
		)
		(pin "H17"
		)
		(pin "E58"
		)
		(pin "E27"
		)
		(pin "F38"
		)
		(pin "H6"
		)
		(pin "G21"
		)
		(pin "D26"
		)
		(pin "J11"
		)
		(pin "B16"
		)
		(pin "B59"
		)
		(pin "A5"
		)
		(pin "K58"
		)
		(pin "L48"
		)
		(pin "A58"
		)
		(pin "F61"
		)
		(pin "K15"
		)
		(pin "G23"
		)
		(pin "E4"
		)
		(pin "H31"
		)
		(pin "K10"
		)
		(pin "D65"
		)
		(pin "G34"
		)
		(pin "L38"
		)
		(pin "K33"
		)
		(pin "C43"
		)
		(pin "F18"
		)
		(pin "E35"
		)
		(pin "D48"
		)
		(pin "G18"
		)
		(pin "K9"
		)
		(pin "C53"
		)
		(pin "E6"
		)
		(pin "C55"
		)
		(pin "J8"
		)
		(pin "D35"
		)
		(pin "F48"
		)
		(pin "E44"
		)
		(pin "B55"
		)
		(pin "E34"
		)
		(pin "G11"
		)
		(pin "G61"
		)
		(pin "K51"
		)
		(pin "K20"
		)
		(pin "A49"
		)
		(pin "H23"
		)
		(pin "C62"
		)
		(pin "B24"
		)
		(pin "G2"
		)
		(pin "B14"
		)
		(pin "G22"
		)
		(pin "A60"
		)
		(pin "K27"
		)
		(pin "H54"
		)
		(pin "B7"
		)
		(pin "A61"
		)
		(pin "D56"
		)
		(pin "G32"
		)
		(pin "B26"
		)
		(pin "B44"
		)
		(pin "H38"
		)
		(pin "C49"
		)
		(pin "D15"
		)
		(pin "B49"
		)
		(pin "B17"
		)
		(pin "F35"
		)
		(pin "B39"
		)
		(pin "F5"
		)
		(pin "J3"
		)
		(pin "J46"
		)
		(pin "J28"
		)
		(pin "J36"
		)
		(pin "J25"
		)
		(pin "J32"
		)
		(pin "L22"
		)
		(pin "K22"
		)
		(pin "J20"
		)
		(pin "C32"
		)
		(pin "F10"
		)
		(pin "G16"
		)
		(pin "F55"
		)
		(pin "K40"
		)
		(pin "H20"
		)
		(pin "K32"
		)
		(pin "G3"
		)
		(pin "A32"
		)
		(pin "J10"
		)
		(pin "C13"
		)
		(pin "L55"
		)
		(pin "G46"
		)
		(pin "G35"
		)
		(pin "L26"
		)
		(pin "E60"
		)
		(pin "J23"
		)
		(pin "J22"
		)
		(pin "A21"
		)
		(pin "L39"
		)
		(pin "C36"
		)
		(pin "L36"
		)
		(pin "G17"
		)
		(pin "J58"
		)
		(pin "K52"
		)
		(pin "B25"
		)
		(pin "E11"
		)
		(pin "B36"
		)
		(pin "A52"
		)
		(pin "B35"
		)
		(pin "D3"
		)
		(pin "K21"
		)
		(pin "E26"
		)
		(pin "F23"
		)
		(pin "F26"
		)
		(pin "G9"
		)
		(pin "D61"
		)
		(pin "C37"
		)
		(pin "K23"
		)
		(pin "G28"
		)
		(pin "H34"
		)
		(pin "D30"
		)
		(pin "H50"
		)
		(pin "G49"
		)
		(pin "B47"
		)
		(pin "B31"
		)
		(pin "A18"
		)
		(pin "J17"
		)
		(pin "C8"
		)
		(pin "C26"
		)
		(pin "G29"
		)
		(pin "E53"
		)
		(pin "G8"
		)
		(pin "K34"
		)
		(pin "K31"
		)
		(pin "G31"
		)
		(pin "K59"
		)
		(pin "L61"
		)
		(pin "C9"
		)
		(pin "D14"
		)
		(pin "K39"
		)
		(pin "C60"
		)
		(pin "F17"
		)
		(pin "B10"
		)
		(pin "L33"
		)
		(pin "H11"
		)
		(pin "L13"
		)
		(pin "D31"
		)
		(pin "F33"
		)
		(pin "A39"
		)
		(pin "A6"
		)
		(pin "C57"
		)
		(pin "H8"
		)
		(pin "G24"
		)
		(pin "B19"
		)
		(pin "F53"
		)
		(pin "K38"
		)
		(pin "A23"
		)
		(pin "C59"
		)
		(pin "J56"
		)
		(pin "D54"
		)
		(pin "F4"
		)
		(pin "A4"
		)
		(pin "F15"
		)
		(pin "G55"
		)
		(pin "E55"
		)
		(pin "J45"
		)
		(pin "D58"
		)
		(pin "J44"
		)
		(pin "K41"
		)
		(pin "A11"
		)
		(pin "G62"
		)
		(pin "J6"
		)
		(pin "H2"
		)
		(pin "L7"
		)
		(pin "C35"
		)
		(pin "L4"
		)
		(pin "E10"
		)
		(pin "A7"
		)
		(pin "L28"
		)
		(pin "K3"
		)
		(pin "J1"
		)
		(pin "K61"
		)
		(pin "G37"
		)
		(pin "L58"
		)
		(pin "A53"
		)
		(pin "L40"
		)
		(pin "F22"
		)
		(pin "K18"
		)
		(pin "D38"
		)
		(pin "K11"
		)
		(pin "H58"
		)
		(pin "A62"
		)
		(pin "K35"
		)
		(pin "D64"
		)
		(pin "G44"
		)
		(pin "H52"
		)
		(pin "H14"
		)
		(pin "K44"
		)
		(pin "F30"
		)
		(pin "D11"
		)
		(pin "C39"
		)
		(pin "K8"
		)
		(pin "F29"
		)
		(pin "F58"
		)
		(pin "B8"
		)
		(pin "B57"
		)
		(pin "B23"
		)
		(pin "G10"
		)
		(pin "K55"
		)
		(pin "G25"
		)
		(pin "L37"
		)
		(pin "H27"
		)
		(pin "H3"
		)
		(pin "F54"
		)
		(pin "K19"
		)
		(pin "G45"
		)
		(pin "L11"
		)
		(pin "J16"
		)
		(pin "K60"
		)
		(pin "B40"
		)
		(pin "J62"
		)
		(pin "K63"
		)
		(pin "H57"
		)
		(pin "L19"
		)
		(pin "L17"
		)
		(pin "C63"
		)
		(pin "E8"
		)
		(pin "D25"
		)
		(pin "C1"
		)
		(pin "C2"
		)
		(pin "B3"
		)
		(pin "B63"
		)
		(pin "C65"
		)
		(pin "K26"
		)
		(pin "A26"
		)
		(pin "G43"
		)
		(pin "H60"
		)
		(pin "F24"
		)
		(pin "H24"
		)
		(pin "J27"
		)
		(pin "C17"
		)
		(pin "F11"
		)
		(pin "F19"
		)
		(pin "J61"
		)
		(pin "K14"
		)
		(pin "K57"
		)
		(pin "L32"
		)
		(pin "B62"
		)
		(pin "D22"
		)
		(pin "D34"
		)
		(pin "L63"
		)
		(pin "B41"
		)
		(pin "K30"
		)
		(pin "B37"
		)
		(pin "K4"
		)
		(instances
			(project ""
				(path ""
					(reference "J1")
					(unit 6)
				)
			)
		)
	)
	(symbol
		(lib_id "antmicroResistors0402:R_33R_0402")
		(at 257.81 262.89 0)
		(unit 1)
		(exclude_from_sim no)
		(in_bom yes)
		(on_board yes)
		(dnp no)
		(property "Reference" "R8"
			(at 255.27 261.62 0)
			(effects
				(font
					(size 1.27 1.27)
					(thickness 0.15)
				)
			)
		)
		(property "Value" "R_33R_0402"
			(at 278.13 275.59 0)
			(effects
				(font
					(size 1.27 1.27)
					(thickness 0.15)
				)
				(justify left bottom)
				(hide yes)
			)
		)
		(property "Footprint" "antmicro-footprints:R_0402_1005Metric"
			(at 278.13 278.13 0)
			(effects
				(font
					(size 1.27 1.27)
					(thickness 0.15)
				)
				(justify left bottom)
				(hide yes)
			)
		)
		(property "Datasheet" "https://www.bourns.com/docs/product-datasheets/cr.pdf"
			(at 278.13 280.67 0)
			(effects
				(font
					(size 1.27 1.27)
					(thickness 0.15)
				)
				(justify left bottom)
				(hide yes)
			)
		)
		(property "Description" "SMD Chip Resistor, 33 ohm, ± 1%, 62.5 mW, 0402 [1005 Metric], Thick Film, General Purpose"
			(at 257.81 262.89 0)
			(effects
				(font
					(size 1.27 1.27)
				)
				(hide yes)
			)
		)
		(property "MPN" "CR0402-FX-33R0GLF"
			(at 278.13 283.21 0)
			(effects
				(font
					(size 1.27 1.27)
					(thickness 0.15)
				)
				(justify left bottom)
				(hide yes)
			)
		)
		(property "Manufacturer" "Bourns"
			(at 278.13 285.75 0)
			(effects
				(font
					(size 1.27 1.27)
					(thickness 0.15)
				)
				(justify left bottom)
				(hide yes)
			)
		)
		(property "License" "Apache-2.0"
			(at 278.13 288.29 0)
			(effects
				(font
					(size 1.27 1.27)
					(thickness 0.15)
				)
				(justify left bottom)
				(hide yes)
			)
		)
		(property "Author" "Antmicro"
			(at 278.13 290.83 0)
			(effects
				(font
					(size 1.27 1.27)
					(thickness 0.15)
				)
				(justify left bottom)
				(hide yes)
			)
		)
		(property "Val" "33R"
			(at 264.795 261.62 0)
			(effects
				(font
					(size 1.27 1.27)
					(thickness 0.15)
				)
			)
		)
		(property "Tolerance" "1%"
			(at 278.13 273.05 0)
			(effects
				(font
					(size 1.27 1.27)
				)
				(justify left bottom)
				(hide yes)
			)
		)
		(pin "2"
		)
		(pin "1"
		)
		(instances
			(project "jetson-agx-thor-baseboard"
				(path ""
					(reference "R8")
					(unit 1)
				)
			)
		)
	)
	(symbol
		(lib_id "antmicroOscillators:Oscillator_156.25MHz_AK3LPHEF1")
		(at 223.52 234.95 0)
		(unit 1)
		(exclude_from_sim no)
		(in_bom yes)
		(on_board yes)
		(dnp no)
		(fields_autoplaced yes)
		(property "Reference" "Y5"
			(at 233.045 224.79 0)
			(effects
				(font
					(size 1.27 1.27)
					(thickness 0.15)
				)
			)
		)
		(property "Value" "Oscillator_156.25MHz_AK3LPHEF1"
			(at 243.84 255.27 0)
			(effects
				(font
					(size 1.27 1.27)
					(thickness 0.15)
				)
				(justify left bottom)
				(hide yes)
			)
		)
		(property "Footprint" "antmicro-footprints:Oscillator_SMD_Abracon_AK3LPHEF1_3.2x2.5x1mm"
			(at 243.84 257.81 0)
			(effects
				(font
					(size 1.27 1.27)
					(thickness 0.15)
				)
				(justify left bottom)
				(hide yes)
			)
		)
		(property "Datasheet" "https://eu.mouser.com/datasheet/2/3/AK3LP-3318362.pdf"
			(at 243.84 260.35 0)
			(effects
				(font
					(size 1.27 1.27)
					(thickness 0.15)
				)
				(justify left bottom)
				(hide yes)
			)
		)
		(property "Description" "156.25 MHz XO (Standard) HCSL Oscillator 3.3V Enable/Disable 6-SMD, +/-25ppm"
			(at 243.84 267.97 0)
			(effects
				(font
					(size 1.27 1.27)
				)
				(justify left bottom)
				(hide yes)
			)
		)
		(property "MPN" "AK3LPHEF1-156.2500T"
			(at 233.045 227.33 0)
			(effects
				(font
					(size 1.27 1.27)
					(thickness 0.15)
				)
			)
		)
		(property "Manufacturer" "Abracon"
			(at 243.84 252.73 0)
			(effects
				(font
					(size 1.27 1.27)
					(thickness 0.15)
				)
				(justify left bottom)
				(hide yes)
			)
		)
		(property "Val" "156.25MHz"
			(at 233.045 229.87 0)
			(effects
				(font
					(size 1.27 1.27)
					(thickness 0.15)
				)
			)
		)
		(property "Author" "Antmicro"
			(at 243.84 262.89 0)
			(effects
				(font
					(size 1.27 1.27)
					(thickness 0.15)
				)
				(justify left bottom)
				(hide yes)
			)
		)
		(property "License" "Apache-2.0"
			(at 243.84 265.43 0)
			(effects
				(font
					(size 1.27 1.27)
					(thickness 0.15)
				)
				(justify left bottom)
				(hide yes)
			)
		)
		(pin "4"
		)
		(pin "5"
		)
		(pin "6"
		)
		(pin "2"
		)
		(pin "3"
		)
		(pin "1"
		)
		(instances
			(project ""
				(path ""
					(reference "Y5")
					(unit 1)
				)
			)
		)
	)
	(symbol
		(lib_id "antmicropower:GND")
		(at 130.81 278.13 0)
		(mirror y)
		(unit 1)
		(exclude_from_sim no)
		(in_bom yes)
		(on_board yes)
		(dnp no)
		(property "Reference" "#PWR0499"
			(at 121.92 280.67 0)
			(effects
				(font
					(size 1.27 1.27)
					(thickness 0.15)
				)
				(justify left bottom)
				(hide yes)
			)
		)
		(property "Value" "GND"
			(at 130.81 281.94 0)
			(effects
				(font
					(size 1.27 1.27)
					(thickness 0.15)
				)
			)
		)
		(property "Footprint" ""
			(at 121.92 285.75 0)
			(effects
				(font
					(size 1.27 1.27)
					(thickness 0.15)
				)
				(justify left bottom)
				(hide yes)
			)
		)
		(property "Datasheet" ""
			(at 121.92 290.83 0)
			(effects
				(font
					(size 1.27 1.27)
					(thickness 0.15)
				)
				(justify left bottom)
				(hide yes)
			)
		)
		(property "Description" ""
			(at 130.81 278.13 0)
			(effects
				(font
					(size 1.27 1.27)
				)
				(hide yes)
			)
		)
		(property "Author" "Antmicro"
			(at 121.92 285.75 0)
			(effects
				(font
					(size 1.27 1.27)
					(thickness 0.15)
				)
				(justify left bottom)
				(hide yes)
			)
		)
		(property "License" "Apache-2.0"
			(at 121.92 288.29 0)
			(effects
				(font
					(size 1.27 1.27)
					(thickness 0.15)
				)
				(justify left bottom)
				(hide yes)
			)
		)
		(pin "1"
		)
		(instances
			(project "jetson-agx-thor-baseboard"
				(path ""
					(reference "#PWR0499")
					(unit 1)
				)
			)
		)
	)
	(symbol
		(lib_id "antmicroCapacitors0402:C_100n_0402")
		(at 205.74 269.24 270)
		(mirror x)
		(unit 1)
		(exclude_from_sim no)
		(in_bom yes)
		(on_board yes)
		(dnp no)
		(property "Reference" "C11"
			(at 203.2 265.4236 90)
			(effects
				(font
					(size 1.27 1.27)
					(thickness 0.15)
				)
				(justify right)
			)
		)
		(property "Value" "C_100n_0402"
			(at 195.58 248.92 0)
			(effects
				(font
					(size 1.27 1.27)
					(thickness 0.15)
				)
				(justify left bottom)
				(hide yes)
			)
		)
		(property "Footprint" "antmicro-footprints:C_0402_1005Metric"
			(at 193.04 248.92 0)
			(effects
				(font
					(size 1.27 1.27)
					(thickness 0.15)
				)
				(justify left bottom)
				(hide yes)
			)
		)
		(property "Datasheet" "https://www.murata.com/products/productdetail?partno=GRM155R61H104KE14%23"
			(at 190.5 248.92 0)
			(effects
				(font
					(size 1.27 1.27)
					(thickness 0.15)
				)
				(justify left bottom)
				(hide yes)
			)
		)
		(property "Description" "SMD Multilayer Ceramic Capacitor, 0.1 µF, 50 V, 0402 [1005 Metric], ± 10%, X5R, GRM Series"
			(at 205.74 269.24 0)
			(effects
				(font
					(size 1.27 1.27)
				)
				(hide yes)
			)
		)
		(property "MPN" "GRM155R61H104KE14D"
			(at 187.96 248.92 0)
			(effects
				(font
					(size 1.27 1.27)
					(thickness 0.15)
				)
				(justify left bottom)
				(hide yes)
			)
		)
		(property "Manufacturer" "Murata"
			(at 185.42 248.92 0)
			(effects
				(font
					(size 1.27 1.27)
					(thickness 0.15)
				)
				(justify left bottom)
				(hide yes)
			)
		)
		(property "License" "Apache-2.0"
			(at 182.88 248.92 0)
			(effects
				(font
					(size 1.27 1.27)
					(thickness 0.15)
				)
				(justify left bottom)
				(hide yes)
			)
		)
		(property "Author" "Antmicro"
			(at 180.34 248.92 0)
			(effects
				(font
					(size 1.27 1.27)
					(thickness 0.15)
				)
				(justify left bottom)
				(hide yes)
			)
		)
		(property "Val" "100n"
			(at 203.2 267.9636 90)
			(effects
				(font
					(size 1.27 1.27)
					(thickness 0.15)
				)
				(justify right)
			)
		)
		(property "Voltage" "50V"
			(at 177.8 248.92 0)
			(effects
				(font
					(size 1.27 1.27)
				)
				(justify left bottom)
				(hide yes)
			)
		)
		(property "Dielectric" "X5R"
			(at 175.26 248.92 0)
			(effects
				(font
					(size 1.27 1.27)
				)
				(justify left bottom)
				(hide yes)
			)
		)
		(pin "1"
		)
		(pin "2"
		)
		(instances
			(project "jetson-agx-thor-baseboard"
				(path ""
					(reference "C11")
					(unit 1)
				)
			)
		)
	)
	(symbol
		(lib_id "antmicropower:+3V3_AON")
		(at 116.84 256.54 0)
		(mirror y)
		(unit 1)
		(exclude_from_sim no)
		(in_bom yes)
		(on_board yes)
		(dnp no)
		(property "Reference" "#PWR0501"
			(at 116.84 260.35 0)
			(effects
				(font
					(size 1.27 1.27)
				)
				(hide yes)
			)
		)
		(property "Value" "+1V8"
			(at 116.84 252.73 0)
			(effects
				(font
					(size 1.27 1.27)
				)
			)
		)
		(property "Footprint" ""
			(at 116.84 256.54 0)
			(effects
				(font
					(size 1.27 1.27)
				)
				(hide yes)
			)
		)
		(property "Datasheet" ""
			(at 116.84 256.54 0)
			(effects
				(font
					(size 1.27 1.27)
				)
				(hide yes)
			)
		)
		(property "Description" ""
			(at 116.84 256.54 0)
			(effects
				(font
					(size 1.27 1.27)
				)
				(hide yes)
			)
		)
		(pin "1"
		)
		(instances
			(project "jetson-agx-thor-baseboard"
				(path ""
					(reference "#PWR0501")
					(unit 1)
				)
			)
		)
	)
	(symbol
		(lib_id "antmicropower:GND")
		(at 266.7 273.05 0)
		(unit 1)
		(exclude_from_sim no)
		(in_bom yes)
		(on_board yes)
		(dnp no)
		(property "Reference" "#PWR0342"
			(at 275.59 275.59 0)
			(effects
				(font
					(size 1.27 1.27)
					(thickness 0.15)
				)
				(justify left bottom)
				(hide yes)
			)
		)
		(property "Value" "GND"
			(at 266.7 276.86 0)
			(effects
				(font
					(size 1.27 1.27)
					(thickness 0.15)
				)
			)
		)
		(property "Footprint" ""
			(at 275.59 280.67 0)
			(effects
				(font
					(size 1.27 1.27)
					(thickness 0.15)
				)
				(justify left bottom)
				(hide yes)
			)
		)
		(property "Datasheet" ""
			(at 275.59 285.75 0)
			(effects
				(font
					(size 1.27 1.27)
					(thickness 0.15)
				)
				(justify left bottom)
				(hide yes)
			)
		)
		(property "Description" ""
			(at 266.7 273.05 0)
			(effects
				(font
					(size 1.27 1.27)
				)
				(hide yes)
			)
		)
		(property "Author" "Antmicro"
			(at 275.59 280.67 0)
			(effects
				(font
					(size 1.27 1.27)
					(thickness 0.15)
				)
				(justify left bottom)
				(hide yes)
			)
		)
		(property "License" "Apache-2.0"
			(at 275.59 283.21 0)
			(effects
				(font
					(size 1.27 1.27)
					(thickness 0.15)
				)
				(justify left bottom)
				(hide yes)
			)
		)
		(pin "1"
		)
		(instances
			(project "jetson-agx-thor-baseboard"
				(path ""
					(reference "#PWR0342")
					(unit 1)
				)
			)
		)
	)
	(symbol
		(lib_id "antmicroCapacitors0402:C_100n_0402")
		(at 373.38 110.49 0)
		(mirror x)
		(unit 1)
		(exclude_from_sim no)
		(in_bom yes)
		(on_board yes)
		(dnp no)
		(property "Reference" "C343"
			(at 382.016 109.22 0)
			(effects
				(font
					(size 1.27 1.27)
				)
				(justify right)
			)
		)
		(property "Value" "C_100n_0402"
			(at 393.7 100.33 0)
			(effects
				(font
					(size 1.27 1.27)
					(thickness 0.15)
				)
				(justify left bottom)
				(hide yes)
			)
		)
		(property "Footprint" "antmicro-footprints:C_0402_1005Metric"
			(at 393.7 97.79 0)
			(effects
				(font
					(size 1.27 1.27)
					(thickness 0.15)
				)
				(justify left bottom)
				(hide yes)
			)
		)
		(property "Datasheet" "https://www.murata.com/products/productdetail?partno=GRM155R61H104KE14%23"
			(at 393.7 95.25 0)
			(effects
				(font
					(size 1.27 1.27)
					(thickness 0.15)
				)
				(justify left bottom)
				(hide yes)
			)
		)
		(property "Description" "SMD Multilayer Ceramic Capacitor, 0.1 µF, 50 V, 0402 [1005 Metric], ± 10%, X5R, GRM Series"
			(at 373.38 110.49 0)
			(effects
				(font
					(size 1.27 1.27)
				)
				(hide yes)
			)
		)
		(property "Manufacturer" "Murata"
			(at 393.7 90.17 0)
			(effects
				(font
					(size 1.27 1.27)
					(thickness 0.15)
				)
				(justify left bottom)
				(hide yes)
			)
		)
		(property "MPN" "GRM155R61H104KE14D"
			(at 393.7 92.71 0)
			(effects
				(font
					(size 1.27 1.27)
					(thickness 0.15)
				)
				(justify left bottom)
				(hide yes)
			)
		)
		(property "Val" "100n"
			(at 374.904 109.474 0)
			(effects
				(font
					(size 1.27 1.27)
					(thickness 0.15)
				)
				(justify right)
			)
		)
		(property "License" "Apache-2.0"
			(at 393.7 87.63 0)
			(effects
				(font
					(size 1.27 1.27)
					(thickness 0.15)
				)
				(justify left bottom)
				(hide yes)
			)
		)
		(property "Author" "Antmicro"
			(at 393.7 85.09 0)
			(effects
				(font
					(size 1.27 1.27)
					(thickness 0.15)
				)
				(justify left bottom)
				(hide yes)
			)
		)
		(property "Voltage" "50V"
			(at 393.7 82.55 0)
			(effects
				(font
					(size 1.27 1.27)
				)
				(justify left bottom)
				(hide yes)
			)
		)
		(property "Dielectric" "X5R"
			(at 393.7 80.01 0)
			(effects
				(font
					(size 1.27 1.27)
				)
				(justify left bottom)
				(hide yes)
			)
		)
		(pin "1"
		)
		(pin "2"
		)
		(instances
			(project "jetson-agx-thor-baseboard"
				(path ""
					(reference "C343")
					(unit 1)
				)
			)
		)
	)
	(symbol
		(lib_id "antmicroResistors0402:R_0R_0402")
		(at 62.23 243.84 0)
		(mirror y)
		(unit 1)
		(exclude_from_sim no)
		(in_bom no)
		(on_board yes)
		(dnp yes)
		(property "Reference" "R292"
			(at 64.77 242.57 0)
			(effects
				(font
					(size 1.27 1.27)
					(thickness 0.15)
				)
			)
		)
		(property "Value" "R_0R_0402"
			(at 41.91 256.54 0)
			(effects
				(font
					(size 1.27 1.27)
					(thickness 0.15)
				)
				(justify left bottom)
				(hide yes)
			)
		)
		(property "Footprint" "antmicro-footprints:R_0402_1005Metric"
			(at 41.91 259.08 0)
			(effects
				(font
					(size 1.27 1.27)
					(thickness 0.15)
				)
				(justify left bottom)
				(hide yes)
			)
		)
		(property "Datasheet" "https://industrial.panasonic.com/cdbs/www-data/pdf/RDA0000/AOA0000C301.pdf"
			(at 41.91 261.62 0)
			(effects
				(font
					(size 1.27 1.27)
					(thickness 0.15)
				)
				(justify left bottom)
				(hide yes)
			)
		)
		(property "Description" "SMD Chip Resistor, Jumper, 0 ohm, 100 mW, 0402 [1005 Metric], Thick Film, General Purpose"
			(at 62.23 243.84 0)
			(effects
				(font
					(size 1.27 1.27)
				)
				(hide yes)
			)
		)
		(property "MPN" "ERJ2GE0R00X"
			(at 41.91 264.16 0)
			(effects
				(font
					(size 1.27 1.27)
					(thickness 0.15)
				)
				(justify left bottom)
				(hide yes)
			)
		)
		(property "Manufacturer" "Panasonic"
			(at 41.91 266.7 0)
			(effects
				(font
					(size 1.27 1.27)
					(thickness 0.15)
				)
				(justify left bottom)
				(hide yes)
			)
		)
		(property "License" "Apache-2.0"
			(at 41.91 269.24 0)
			(effects
				(font
					(size 1.27 1.27)
					(thickness 0.15)
				)
				(justify left bottom)
				(hide yes)
			)
		)
		(property "Author" "Antmicro"
			(at 41.91 271.78 0)
			(effects
				(font
					(size 1.27 1.27)
					(thickness 0.15)
				)
				(justify left bottom)
				(hide yes)
			)
		)
		(property "Val" "0R"
			(at 55.88 242.57 0)
			(effects
				(font
					(size 1.27 1.27)
					(thickness 0.15)
				)
			)
		)
		(property "Tolerance" "~"
			(at 41.91 254 0)
			(effects
				(font
					(size 1.27 1.27)
				)
				(justify left bottom)
				(hide yes)
			)
		)
		(property "Current" "1A"
			(at 41.91 274.32 0)
			(effects
				(font
					(size 1.27 1.27)
					(thickness 0.15)
				)
				(justify left bottom)
				(hide yes)
			)
		)
		(pin "2"
		)
		(pin "1"
		)
		(instances
			(project "jetson-agx-thor-baseboard"
				(path ""
					(reference "R292")
					(unit 1)
				)
			)
		)
	)
	(symbol
		(lib_id "antmicroB2BConnectors:Hermaphroditic_Molex_203456-0003_CUSTOM_Jetson_AGX_Thor_H8mm")
		(at 307.34 35.56 0)
		(unit 5)
		(exclude_from_sim no)
		(in_bom yes)
		(on_board yes)
		(dnp no)
		(fields_autoplaced yes)
		(property "Reference" "J1"
			(at 330.2 27.94 0)
			(effects
				(font
					(size 1.27 1.27)
				)
			)
		)
		(property "Value" "Hermaphroditic_Molex_203456-0003_CUSTOM_Jetson_AGX_Thor_H8mm"
			(at 383.794 41.656 0)
			(effects
				(font
					(size 1.27 1.27)
				)
				(justify left bottom)
				(hide yes)
			)
		)
		(property "Footprint" "antmicro-footprints:Conn_Hermaphroditic_Molex_203456-0003_mirrored"
			(at 383.794 43.942 0)
			(effects
				(font
					(size 1.27 1.27)
				)
				(justify left bottom)
				(hide yes)
			)
		)
		(property "Datasheet" "https://www.molex.com/content/dam/molex/molex-dot-com/products/automated/en-us/salesdrawingpdf/203/203456/2034560003_sd.pdf?inline"
			(at 383.794 46.228 0)
			(effects
				(font
					(size 1.27 1.27)
				)
				(justify left bottom)
				(hide yes)
			)
		)
		(property "Description" "Mirror Mezz Hermaphroditic Connector, 5.50mm Connector Height, BGA-Attach Mounting, 7 Pair, 11 Row, 699 Circuits, 0.76µm Gold Plating, without Pegs"
			(at 383.794 54.864 0)
			(effects
				(font
					(size 1.27 1.27)
				)
				(justify left bottom)
				(hide yes)
			)
		)
		(property "MPN" "203456-0003"
			(at 330.2 30.48 0)
			(effects
				(font
					(size 1.27 1.27)
				)
			)
		)
		(property "Manufacturer" "Molex"
			(at 383.794 48.514 0)
			(effects
				(font
					(size 1.27 1.27)
				)
				(justify left bottom)
				(hide yes)
			)
		)
		(property "Author" "Antmicro"
			(at 383.794 50.546 0)
			(effects
				(font
					(size 1.27 1.27)
				)
				(justify left bottom)
				(hide yes)
			)
		)
		(property "License" "Apache-2.0"
			(at 383.794 52.578 0)
			(effects
				(font
					(size 1.27 1.27)
				)
				(justify left bottom)
				(hide yes)
			)
		)
		(pin "J37"
		)
		(pin "D37"
		)
		(pin "C40"
		)
		(pin "J40"
		)
		(pin "C30"
		)
		(pin "D28"
		)
		(pin "F57"
		)
		(pin "F45"
		)
		(pin "B48"
		)
		(pin "F46"
		)
		(pin "C41"
		)
		(pin "D23"
		)
		(pin "G48"
		)
		(pin "C42"
		)
		(pin "J5"
		)
		(pin "E56"
		)
		(pin "D27"
		)
		(pin "C27"
		)
		(pin "E28"
		)
		(pin "D63"
		)
		(pin "A40"
		)
		(pin "J21"
		)
		(pin "L24"
		)
		(pin "L59"
		)
		(pin "B27"
		)
		(pin "D1"
		)
		(pin "C16"
		)
		(pin "H12"
		)
		(pin "H19"
		)
		(pin "F9"
		)
		(pin "A42"
		)
		(pin "A41"
		)
		(pin "B42"
		)
		(pin "E7"
		)
		(pin "B43"
		)
		(pin "L54"
		)
		(pin "A57"
		)
		(pin "J42"
		)
		(pin "B12"
		)
		(pin "F63"
		)
		(pin "J38"
		)
		(pin "J41"
		)
		(pin "L43"
		)
		(pin "D59"
		)
		(pin "J65"
		)
		(pin "H26"
		)
		(pin "G19"
		)
		(pin "G7"
		)
		(pin "D12"
		)
		(pin "F34"
		)
		(pin "G42"
		)
		(pin "G41"
		)
		(pin "H42"
		)
		(pin "E30"
		)
		(pin "L62"
		)
		(pin "L49"
		)
		(pin "H43"
		)
		(pin "F27"
		)
		(pin "G64"
		)
		(pin "J54"
		)
		(pin "F39"
		)
		(pin "E38"
		)
		(pin "D8"
		)
		(pin "H30"
		)
		(pin "B33"
		)
		(pin "G12"
		)
		(pin "E39"
		)
		(pin "E5"
		)
		(pin "E41"
		)
		(pin "E42"
		)
		(pin "H16"
		)
		(pin "F42"
		)
		(pin "F43"
		)
		(pin "L56"
		)
		(pin "F21"
		)
		(pin "B21"
		)
		(pin "F20"
		)
		(pin "C19"
		)
		(pin "L15"
		)
		(pin "F50"
		)
		(pin "F37"
		)
		(pin "J60"
		)
		(pin "E18"
		)
		(pin "E64"
		)
		(pin "E19"
		)
		(pin "B13"
		)
		(pin "D9"
		)
		(pin "K56"
		)
		(pin "D5"
		)
		(pin "A19"
		)
		(pin "D45"
		)
		(pin "L12"
		)
		(pin "C47"
		)
		(pin "E13"
		)
		(pin "E46"
		)
		(pin "C24"
		)
		(pin "H64"
		)
		(pin "A24"
		)
		(pin "F3"
		)
		(pin "L27"
		)
		(pin "H40"
		)
		(pin "C20"
		)
		(pin "G13"
		)
		(pin "K29"
		)
		(pin "H65"
		)
		(pin "A9"
		)
		(pin "A13"
		)
		(pin "A30"
		)
		(pin "B34"
		)
		(pin "E12"
		)
		(pin "C11"
		)
		(pin "E23"
		)
		(pin "D7"
		)
		(pin "D18"
		)
		(pin "F65"
		)
		(pin "D53"
		)
		(pin "H35"
		)
		(pin "A25"
		)
		(pin "C3"
		)
		(pin "J33"
		)
		(pin "H39"
		)
		(pin "B50"
		)
		(pin "A63"
		)
		(pin "G65"
		)
		(pin "B22"
		)
		(pin "B18"
		)
		(pin "E57"
		)
		(pin "D29"
		)
		(pin "D19"
		)
		(pin "F25"
		)
		(pin "F28"
		)
		(pin "L10"
		)
		(pin "C31"
		)
		(pin "G1"
		)
		(pin "E16"
		)
		(pin "E40"
		)
		(pin "E20"
		)
		(pin "D50"
		)
		(pin "D57"
		)
		(pin "F59"
		)
		(pin "J64"
		)
		(pin "D49"
		)
		(pin "E62"
		)
		(pin "E24"
		)
		(pin "J26"
		)
		(pin "K25"
		)
		(pin "G26"
		)
		(pin "H29"
		)
		(pin "B29"
		)
		(pin "B38"
		)
		(pin "C10"
		)
		(pin "F12"
		)
		(pin "A46"
		)
		(pin "K12"
		)
		(pin "E17"
		)
		(pin "F16"
		)
		(pin "H25"
		)
		(pin "K16"
		)
		(pin "J30"
		)
		(pin "D17"
		)
		(pin "K37"
		)
		(pin "B5"
		)
		(pin "E50"
		)
		(pin "D16"
		)
		(pin "D4"
		)
		(pin "G40"
		)
		(pin "H7"
		)
		(pin "A45"
		)
		(pin "H45"
		)
		(pin "C18"
		)
		(pin "G36"
		)
		(pin "B58"
		)
		(pin "A10"
		)
		(pin "L52"
		)
		(pin "G54"
		)
		(pin "G53"
		)
		(pin "D20"
		)
		(pin "K50"
		)
		(pin "H61"
		)
		(pin "C54"
		)
		(pin "H33"
		)
		(pin "H51"
		)
		(pin "H62"
		)
		(pin "F44"
		)
		(pin "H32"
		)
		(pin "C6"
		)
		(pin "L25"
		)
		(pin "A35"
		)
		(pin "D55"
		)
		(pin "L9"
		)
		(pin "F41"
		)
		(pin "A56"
		)
		(pin "J18"
		)
		(pin "K7"
		)
		(pin "D13"
		)
		(pin "A34"
		)
		(pin "G33"
		)
		(pin "A38"
		)
		(pin "D24"
		)
		(pin "H63"
		)
		(pin "C58"
		)
		(pin "J35"
		)
		(pin "J51"
		)
		(pin "E61"
		)
		(pin "E25"
		)
		(pin "E29"
		)
		(pin "E63"
		)
		(pin "L60"
		)
		(pin "D62"
		)
		(pin "G58"
		)
		(pin "J12"
		)
		(pin "J59"
		)
		(pin "H15"
		)
		(pin "K36"
		)
		(pin "J24"
		)
		(pin "A54"
		)
		(pin "D32"
		)
		(pin "F62"
		)
		(pin "B54"
		)
		(pin "D33"
		)
		(pin "G14"
		)
		(pin "A22"
		)
		(pin "C14"
		)
		(pin "L3"
		)
		(pin "E2"
		)
		(pin "B11"
		)
		(pin "C23"
		)
		(pin "A12"
		)
		(pin "G15"
		)
		(pin "C15"
		)
		(pin "A59"
		)
		(pin "J15"
		)
		(pin "J57"
		)
		(pin "C7"
		)
		(pin "J14"
		)
		(pin "G59"
		)
		(pin "G39"
		)
		(pin "E54"
		)
		(pin "A37"
		)
		(pin "L41"
		)
		(pin "A14"
		)
		(pin "A15"
		)
		(pin "L51"
		)
		(pin "K47"
		)
		(pin "L46"
		)
		(pin "G4"
		)
		(pin "B15"
		)
		(pin "C34"
		)
		(pin "K46"
		)
		(pin "H37"
		)
		(pin "J48"
		)
		(pin "J47"
		)
		(pin "B9"
		)
		(pin "F49"
		)
		(pin "C22"
		)
		(pin "J39"
		)
		(pin "J13"
		)
		(pin "G50"
		)
		(pin "L6"
		)
		(pin "G51"
		)
		(pin "L8"
		)
		(pin "H9"
		)
		(pin "B56"
		)
		(pin "L53"
		)
		(pin "C12"
		)
		(pin "E59"
		)
		(pin "K24"
		)
		(pin "E52"
		)
		(pin "A27"
		)
		(pin "A31"
		)
		(pin "E21"
		)
		(pin "K17"
		)
		(pin "H49"
		)
		(pin "E22"
		)
		(pin "H21"
		)
		(pin "J63"
		)
		(pin "K28"
		)
		(pin "B28"
		)
		(pin "E65"
		)
		(pin "G52"
		)
		(pin "D44"
		)
		(pin "D47"
		)
		(pin "B4"
		)
		(pin "F2"
		)
		(pin "L35"
		)
		(pin "C52"
		)
		(pin "L42"
		)
		(pin "E32"
		)
		(pin "E37"
		)
		(pin "E33"
		)
		(pin "E43"
		)
		(pin "E15"
		)
		(pin "G30"
		)
		(pin "D41"
		)
		(pin "J31"
		)
		(pin "E9"
		)
		(pin "F14"
		)
		(pin "L5"
		)
		(pin "E3"
		)
		(pin "L34"
		)
		(pin "C25"
		)
		(pin "J4"
		)
		(pin "K42"
		)
		(pin "G63"
		)
		(pin "A16"
		)
		(pin "L30"
		)
		(pin "E1"
		)
		(pin "A36"
		)
		(pin "L20"
		)
		(pin "J2"
		)
		(pin "K45"
		)
		(pin "A3"
		)
		(pin "L23"
		)
		(pin "A33"
		)
		(pin "A17"
		)
		(pin "H41"
		)
		(pin "C46"
		)
		(pin "L31"
		)
		(pin "H44"
		)
		(pin "F64"
		)
		(pin "A28"
		)
		(pin "C21"
		)
		(pin "F1"
		)
		(pin "A20"
		)
		(pin "B53"
		)
		(pin "A29"
		)
		(pin "E49"
		)
		(pin "G27"
		)
		(pin "E14"
		)
		(pin "H4"
		)
		(pin "H13"
		)
		(pin "F32"
		)
		(pin "F13"
		)
		(pin "E36"
		)
		(pin "D39"
		)
		(pin "H48"
		)
		(pin "K43"
		)
		(pin "F40"
		)
		(pin "G57"
		)
		(pin "C4"
		)
		(pin "K53"
		)
		(pin "D40"
		)
		(pin "H46"
		)
		(pin "H10"
		)
		(pin "C56"
		)
		(pin "L21"
		)
		(pin "G6"
		)
		(pin "H28"
		)
		(pin "K13"
		)
		(pin "L47"
		)
		(pin "C48"
		)
		(pin "D10"
		)
		(pin "D43"
		)
		(pin "A44"
		)
		(pin "D46"
		)
		(pin "C45"
		)
		(pin "J9"
		)
		(pin "C50"
		)
		(pin "L16"
		)
		(pin "B46"
		)
		(pin "E47"
		)
		(pin "H36"
		)
		(pin "B45"
		)
		(pin "C44"
		)
		(pin "L18"
		)
		(pin "D42"
		)
		(pin "A8"
		)
		(pin "C38"
		)
		(pin "E48"
		)
		(pin "K49"
		)
		(pin "L50"
		)
		(pin "K54"
		)
		(pin "J29"
		)
		(pin "K48"
		)
		(pin "C61"
		)
		(pin "D21"
		)
		(pin "K5"
		)
		(pin "C51"
		)
		(pin "H53"
		)
		(pin "J7"
		)
		(pin "A50"
		)
		(pin "H56"
		)
		(pin "A51"
		)
		(pin "H47"
		)
		(pin "H18"
		)
		(pin "G47"
		)
		(pin "D6"
		)
		(pin "B51"
		)
		(pin "G5"
		)
		(pin "B52"
		)
		(pin "H22"
		)
		(pin "L14"
		)
		(pin "D52"
		)
		(pin "E31"
		)
		(pin "J53"
		)
		(pin "B61"
		)
		(pin "G20"
		)
		(pin "B60"
		)
		(pin "L29"
		)
		(pin "F31"
		)
		(pin "G60"
		)
		(pin "F60"
		)
		(pin "D51"
		)
		(pin "F56"
		)
		(pin "G38"
		)
		(pin "J50"
		)
		(pin "L45"
		)
		(pin "J43"
		)
		(pin "F8"
		)
		(pin "J34"
		)
		(pin "E51"
		)
		(pin "A43"
		)
		(pin "F36"
		)
		(pin "B30"
		)
		(pin "B32"
		)
		(pin "L44"
		)
		(pin "K62"
		)
		(pin "D2"
		)
		(pin "L57"
		)
		(pin "E45"
		)
		(pin "H55"
		)
		(pin "A47"
		)
		(pin "H1"
		)
		(pin "C29"
		)
		(pin "B6"
		)
		(pin "B20"
		)
		(pin "C33"
		)
		(pin "J55"
		)
		(pin "C64"
		)
		(pin "F47"
		)
		(pin "A55"
		)
		(pin "D60"
		)
		(pin "J52"
		)
		(pin "F51"
		)
		(pin "H5"
		)
		(pin "C28"
		)
		(pin "F7"
		)
		(pin "A48"
		)
		(pin "H59"
		)
		(pin "K6"
		)
		(pin "D36"
		)
		(pin "F6"
		)
		(pin "F52"
		)
		(pin "J49"
		)
		(pin "J19"
		)
		(pin "C5"
		)
		(pin "G56"
		)
		(pin "H17"
		)
		(pin "E58"
		)
		(pin "E27"
		)
		(pin "F38"
		)
		(pin "H6"
		)
		(pin "G21"
		)
		(pin "D26"
		)
		(pin "J11"
		)
		(pin "B16"
		)
		(pin "B59"
		)
		(pin "A5"
		)
		(pin "K58"
		)
		(pin "L48"
		)
		(pin "A58"
		)
		(pin "F61"
		)
		(pin "K15"
		)
		(pin "G23"
		)
		(pin "E4"
		)
		(pin "H31"
		)
		(pin "K10"
		)
		(pin "D65"
		)
		(pin "G34"
		)
		(pin "L38"
		)
		(pin "K33"
		)
		(pin "C43"
		)
		(pin "F18"
		)
		(pin "E35"
		)
		(pin "D48"
		)
		(pin "G18"
		)
		(pin "K9"
		)
		(pin "C53"
		)
		(pin "E6"
		)
		(pin "C55"
		)
		(pin "J8"
		)
		(pin "D35"
		)
		(pin "F48"
		)
		(pin "E44"
		)
		(pin "B55"
		)
		(pin "E34"
		)
		(pin "G11"
		)
		(pin "G61"
		)
		(pin "K51"
		)
		(pin "K20"
		)
		(pin "A49"
		)
		(pin "H23"
		)
		(pin "C62"
		)
		(pin "B24"
		)
		(pin "G2"
		)
		(pin "B14"
		)
		(pin "G22"
		)
		(pin "A60"
		)
		(pin "K27"
		)
		(pin "H54"
		)
		(pin "B7"
		)
		(pin "A61"
		)
		(pin "D56"
		)
		(pin "G32"
		)
		(pin "B26"
		)
		(pin "B44"
		)
		(pin "H38"
		)
		(pin "C49"
		)
		(pin "D15"
		)
		(pin "B49"
		)
		(pin "B17"
		)
		(pin "F35"
		)
		(pin "B39"
		)
		(pin "F5"
		)
		(pin "J3"
		)
		(pin "J46"
		)
		(pin "J28"
		)
		(pin "J36"
		)
		(pin "J25"
		)
		(pin "J32"
		)
		(pin "L22"
		)
		(pin "K22"
		)
		(pin "J20"
		)
		(pin "C32"
		)
		(pin "F10"
		)
		(pin "G16"
		)
		(pin "F55"
		)
		(pin "K40"
		)
		(pin "H20"
		)
		(pin "K32"
		)
		(pin "G3"
		)
		(pin "A32"
		)
		(pin "J10"
		)
		(pin "C13"
		)
		(pin "L55"
		)
		(pin "G46"
		)
		(pin "G35"
		)
		(pin "L26"
		)
		(pin "E60"
		)
		(pin "J23"
		)
		(pin "J22"
		)
		(pin "A21"
		)
		(pin "L39"
		)
		(pin "C36"
		)
		(pin "L36"
		)
		(pin "G17"
		)
		(pin "J58"
		)
		(pin "K52"
		)
		(pin "B25"
		)
		(pin "E11"
		)
		(pin "B36"
		)
		(pin "A52"
		)
		(pin "B35"
		)
		(pin "D3"
		)
		(pin "K21"
		)
		(pin "E26"
		)
		(pin "F23"
		)
		(pin "F26"
		)
		(pin "G9"
		)
		(pin "D61"
		)
		(pin "C37"
		)
		(pin "K23"
		)
		(pin "G28"
		)
		(pin "H34"
		)
		(pin "D30"
		)
		(pin "H50"
		)
		(pin "G49"
		)
		(pin "B47"
		)
		(pin "B31"
		)
		(pin "A18"
		)
		(pin "J17"
		)
		(pin "C8"
		)
		(pin "C26"
		)
		(pin "G29"
		)
		(pin "E53"
		)
		(pin "G8"
		)
		(pin "K34"
		)
		(pin "K31"
		)
		(pin "G31"
		)
		(pin "K59"
		)
		(pin "L61"
		)
		(pin "C9"
		)
		(pin "D14"
		)
		(pin "K39"
		)
		(pin "C60"
		)
		(pin "F17"
		)
		(pin "B10"
		)
		(pin "L33"
		)
		(pin "H11"
		)
		(pin "L13"
		)
		(pin "D31"
		)
		(pin "F33"
		)
		(pin "A39"
		)
		(pin "A6"
		)
		(pin "C57"
		)
		(pin "H8"
		)
		(pin "G24"
		)
		(pin "B19"
		)
		(pin "F53"
		)
		(pin "K38"
		)
		(pin "A23"
		)
		(pin "C59"
		)
		(pin "J56"
		)
		(pin "D54"
		)
		(pin "F4"
		)
		(pin "A4"
		)
		(pin "F15"
		)
		(pin "G55"
		)
		(pin "E55"
		)
		(pin "J45"
		)
		(pin "D58"
		)
		(pin "J44"
		)
		(pin "K41"
		)
		(pin "A11"
		)
		(pin "G62"
		)
		(pin "J6"
		)
		(pin "H2"
		)
		(pin "L7"
		)
		(pin "C35"
		)
		(pin "L4"
		)
		(pin "E10"
		)
		(pin "A7"
		)
		(pin "L28"
		)
		(pin "K3"
		)
		(pin "J1"
		)
		(pin "K61"
		)
		(pin "G37"
		)
		(pin "L58"
		)
		(pin "A53"
		)
		(pin "L40"
		)
		(pin "F22"
		)
		(pin "K18"
		)
		(pin "D38"
		)
		(pin "K11"
		)
		(pin "H58"
		)
		(pin "A62"
		)
		(pin "K35"
		)
		(pin "D64"
		)
		(pin "G44"
		)
		(pin "H52"
		)
		(pin "H14"
		)
		(pin "K44"
		)
		(pin "F30"
		)
		(pin "D11"
		)
		(pin "C39"
		)
		(pin "K8"
		)
		(pin "F29"
		)
		(pin "F58"
		)
		(pin "B8"
		)
		(pin "B57"
		)
		(pin "B23"
		)
		(pin "G10"
		)
		(pin "K55"
		)
		(pin "G25"
		)
		(pin "L37"
		)
		(pin "H27"
		)
		(pin "H3"
		)
		(pin "F54"
		)
		(pin "K19"
		)
		(pin "G45"
		)
		(pin "L11"
		)
		(pin "J16"
		)
		(pin "K60"
		)
		(pin "B40"
		)
		(pin "J62"
		)
		(pin "K63"
		)
		(pin "H57"
		)
		(pin "L19"
		)
		(pin "L17"
		)
		(pin "C63"
		)
		(pin "E8"
		)
		(pin "D25"
		)
		(pin "C1"
		)
		(pin "C2"
		)
		(pin "B3"
		)
		(pin "B63"
		)
		(pin "C65"
		)
		(pin "K26"
		)
		(pin "A26"
		)
		(pin "G43"
		)
		(pin "H60"
		)
		(pin "F24"
		)
		(pin "H24"
		)
		(pin "J27"
		)
		(pin "C17"
		)
		(pin "F11"
		)
		(pin "F19"
		)
		(pin "J61"
		)
		(pin "K14"
		)
		(pin "K57"
		)
		(pin "L32"
		)
		(pin "B62"
		)
		(pin "D22"
		)
		(pin "D34"
		)
		(pin "L63"
		)
		(pin "B41"
		)
		(pin "K30"
		)
		(pin "B37"
		)
		(pin "K4"
		)
		(instances
			(project ""
				(path ""
					(reference "J1")
					(unit 5)
				)
			)
		)
	)
	(symbol
		(lib_id "antmicroCapacitors0402:C_100n_0402")
		(at 287.02 49.53 0)
		(mirror x)
		(unit 1)
		(exclude_from_sim no)
		(in_bom yes)
		(on_board yes)
		(dnp no)
		(property "Reference" "C317"
			(at 295.656 48.26 0)
			(effects
				(font
					(size 1.27 1.27)
				)
				(justify right)
			)
		)
		(property "Value" "C_100n_0402"
			(at 307.34 39.37 0)
			(effects
				(font
					(size 1.27 1.27)
					(thickness 0.15)
				)
				(justify left bottom)
				(hide yes)
			)
		)
		(property "Footprint" "antmicro-footprints:C_0402_1005Metric"
			(at 307.34 36.83 0)
			(effects
				(font
					(size 1.27 1.27)
					(thickness 0.15)
				)
				(justify left bottom)
				(hide yes)
			)
		)
		(property "Datasheet" "https://www.murata.com/products/productdetail?partno=GRM155R61H104KE14%23"
			(at 307.34 34.29 0)
			(effects
				(font
					(size 1.27 1.27)
					(thickness 0.15)
				)
				(justify left bottom)
				(hide yes)
			)
		)
		(property "Description" "SMD Multilayer Ceramic Capacitor, 0.1 µF, 50 V, 0402 [1005 Metric], ± 10%, X5R, GRM Series"
			(at 287.02 49.53 0)
			(effects
				(font
					(size 1.27 1.27)
				)
				(hide yes)
			)
		)
		(property "Manufacturer" "Murata"
			(at 307.34 29.21 0)
			(effects
				(font
					(size 1.27 1.27)
					(thickness 0.15)
				)
				(justify left bottom)
				(hide yes)
			)
		)
		(property "MPN" "GRM155R61H104KE14D"
			(at 307.34 31.75 0)
			(effects
				(font
					(size 1.27 1.27)
					(thickness 0.15)
				)
				(justify left bottom)
				(hide yes)
			)
		)
		(property "Val" "100n"
			(at 288.544 48.514 0)
			(effects
				(font
					(size 1.27 1.27)
					(thickness 0.15)
				)
				(justify right)
			)
		)
		(property "License" "Apache-2.0"
			(at 307.34 26.67 0)
			(effects
				(font
					(size 1.27 1.27)
					(thickness 0.15)
				)
				(justify left bottom)
				(hide yes)
			)
		)
		(property "Author" "Antmicro"
			(at 307.34 24.13 0)
			(effects
				(font
					(size 1.27 1.27)
					(thickness 0.15)
				)
				(justify left bottom)
				(hide yes)
			)
		)
		(property "Voltage" "50V"
			(at 307.34 21.59 0)
			(effects
				(font
					(size 1.27 1.27)
				)
				(justify left bottom)
				(hide yes)
			)
		)
		(property "Dielectric" "X5R"
			(at 307.34 19.05 0)
			(effects
				(font
					(size 1.27 1.27)
				)
				(justify left bottom)
				(hide yes)
			)
		)
		(pin "1"
		)
		(pin "2"
		)
		(instances
			(project "jetson-agx-thor-baseboard"
				(path ""
					(reference "C317")
					(unit 1)
				)
			)
		)
	)
	(symbol
		(lib_id "antmicroCapacitors0402:C_100n_0402")
		(at 279.4 67.31 0)
		(mirror x)
		(unit 1)
		(exclude_from_sim no)
		(in_bom yes)
		(on_board yes)
		(dnp no)
		(property "Reference" "C324"
			(at 288.29 66.04 0)
			(effects
				(font
					(size 1.27 1.27)
				)
				(justify right)
			)
		)
		(property "Value" "C_100n_0402"
			(at 299.72 57.15 0)
			(effects
				(font
					(size 1.27 1.27)
					(thickness 0.15)
				)
				(justify left bottom)
				(hide yes)
			)
		)
		(property "Footprint" "antmicro-footprints:C_0402_1005Metric"
			(at 299.72 54.61 0)
			(effects
				(font
					(size 1.27 1.27)
					(thickness 0.15)
				)
				(justify left bottom)
				(hide yes)
			)
		)
		(property "Datasheet" "https://www.murata.com/products/productdetail?partno=GRM155R61H104KE14%23"
			(at 299.72 52.07 0)
			(effects
				(font
					(size 1.27 1.27)
					(thickness 0.15)
				)
				(justify left bottom)
				(hide yes)
			)
		)
		(property "Description" "SMD Multilayer Ceramic Capacitor, 0.1 µF, 50 V, 0402 [1005 Metric], ± 10%, X5R, GRM Series"
			(at 279.4 67.31 0)
			(effects
				(font
					(size 1.27 1.27)
				)
				(hide yes)
			)
		)
		(property "Manufacturer" "Murata"
			(at 299.72 46.99 0)
			(effects
				(font
					(size 1.27 1.27)
					(thickness 0.15)
				)
				(justify left bottom)
				(hide yes)
			)
		)
		(property "MPN" "GRM155R61H104KE14D"
			(at 299.72 49.53 0)
			(effects
				(font
					(size 1.27 1.27)
					(thickness 0.15)
				)
				(justify left bottom)
				(hide yes)
			)
		)
		(property "Val" "100n"
			(at 280.924 66.294 0)
			(effects
				(font
					(size 1.27 1.27)
					(thickness 0.15)
				)
				(justify right)
			)
		)
		(property "License" "Apache-2.0"
			(at 299.72 44.45 0)
			(effects
				(font
					(size 1.27 1.27)
					(thickness 0.15)
				)
				(justify left bottom)
				(hide yes)
			)
		)
		(property "Author" "Antmicro"
			(at 299.72 41.91 0)
			(effects
				(font
					(size 1.27 1.27)
					(thickness 0.15)
				)
				(justify left bottom)
				(hide yes)
			)
		)
		(property "Voltage" "50V"
			(at 299.72 39.37 0)
			(effects
				(font
					(size 1.27 1.27)
				)
				(justify left bottom)
				(hide yes)
			)
		)
		(property "Dielectric" "X5R"
			(at 299.72 36.83 0)
			(effects
				(font
					(size 1.27 1.27)
				)
				(justify left bottom)
				(hide yes)
			)
		)
		(pin "1"
		)
		(pin "2"
		)
		(instances
			(project "jetson-agx-thor-baseboard"
				(path ""
					(reference "C324")
					(unit 1)
				)
			)
		)
	)
	(symbol
		(lib_id "antmicroCapacitors0402:C_100n_0402")
		(at 287.02 59.69 0)
		(mirror x)
		(unit 1)
		(exclude_from_sim no)
		(in_bom yes)
		(on_board yes)
		(dnp no)
		(property "Reference" "C321"
			(at 295.656 58.42 0)
			(effects
				(font
					(size 1.27 1.27)
				)
				(justify right)
			)
		)
		(property "Value" "C_100n_0402"
			(at 307.34 49.53 0)
			(effects
				(font
					(size 1.27 1.27)
					(thickness 0.15)
				)
				(justify left bottom)
				(hide yes)
			)
		)
		(property "Footprint" "antmicro-footprints:C_0402_1005Metric"
			(at 307.34 46.99 0)
			(effects
				(font
					(size 1.27 1.27)
					(thickness 0.15)
				)
				(justify left bottom)
				(hide yes)
			)
		)
		(property "Datasheet" "https://www.murata.com/products/productdetail?partno=GRM155R61H104KE14%23"
			(at 307.34 44.45 0)
			(effects
				(font
					(size 1.27 1.27)
					(thickness 0.15)
				)
				(justify left bottom)
				(hide yes)
			)
		)
		(property "Description" "SMD Multilayer Ceramic Capacitor, 0.1 µF, 50 V, 0402 [1005 Metric], ± 10%, X5R, GRM Series"
			(at 287.02 59.69 0)
			(effects
				(font
					(size 1.27 1.27)
				)
				(hide yes)
			)
		)
		(property "Manufacturer" "Murata"
			(at 307.34 39.37 0)
			(effects
				(font
					(size 1.27 1.27)
					(thickness 0.15)
				)
				(justify left bottom)
				(hide yes)
			)
		)
		(property "MPN" "GRM155R61H104KE14D"
			(at 307.34 41.91 0)
			(effects
				(font
					(size 1.27 1.27)
					(thickness 0.15)
				)
				(justify left bottom)
				(hide yes)
			)
		)
		(property "Val" "100n"
			(at 288.544 58.674 0)
			(effects
				(font
					(size 1.27 1.27)
					(thickness 0.15)
				)
				(justify right)
			)
		)
		(property "License" "Apache-2.0"
			(at 307.34 36.83 0)
			(effects
				(font
					(size 1.27 1.27)
					(thickness 0.15)
				)
				(justify left bottom)
				(hide yes)
			)
		)
		(property "Author" "Antmicro"
			(at 307.34 34.29 0)
			(effects
				(font
					(size 1.27 1.27)
					(thickness 0.15)
				)
				(justify left bottom)
				(hide yes)
			)
		)
		(property "Voltage" "50V"
			(at 307.34 31.75 0)
			(effects
				(font
					(size 1.27 1.27)
				)
				(justify left bottom)
				(hide yes)
			)
		)
		(property "Dielectric" "X5R"
			(at 307.34 29.21 0)
			(effects
				(font
					(size 1.27 1.27)
				)
				(justify left bottom)
				(hide yes)
			)
		)
		(pin "1"
		)
		(pin "2"
		)
		(instances
			(project "jetson-agx-thor-baseboard"
				(path ""
					(reference "C321")
					(unit 1)
				)
			)
		)
	)
	(symbol
		(lib_id "antmicroResistors0402:R_10k_0402")
		(at 142.24 267.97 270)
		(mirror x)
		(unit 1)
		(exclude_from_sim no)
		(in_bom no)
		(on_board yes)
		(dnp yes)
		(fields_autoplaced yes)
		(property "Reference" "R342"
			(at 144.78 264.16 90)
			(effects
				(font
					(size 1.27 1.27)
					(thickness 0.15)
				)
				(justify left)
			)
		)
		(property "Value" "R_10k_0402"
			(at 129.54 247.65 0)
			(effects
				(font
					(size 1.27 1.27)
					(thickness 0.15)
				)
				(justify left bottom)
				(hide yes)
			)
		)
		(property "Footprint" "antmicro-footprints:R_0402_1005Metric"
			(at 127 247.65 0)
			(effects
				(font
					(size 1.27 1.27)
					(thickness 0.15)
				)
				(justify left bottom)
				(hide yes)
			)
		)
		(property "Datasheet" "https://www.bourns.com/docs/product-datasheets/cr.pdf"
			(at 124.46 247.65 0)
			(effects
				(font
					(size 1.27 1.27)
					(thickness 0.15)
				)
				(justify left bottom)
				(hide yes)
			)
		)
		(property "Description" "SMD Chip Resistor, 10 kohm, ± 1%, 62.5 mW, 0402 [1005 Metric], Thick Film, General Purpose"
			(at 142.24 267.97 0)
			(effects
				(font
					(size 1.27 1.27)
				)
				(hide yes)
			)
		)
		(property "MPN" "CR0402-FX-1002GLF"
			(at 121.92 247.65 0)
			(effects
				(font
					(size 1.27 1.27)
					(thickness 0.15)
				)
				(justify left bottom)
				(hide yes)
			)
		)
		(property "Manufacturer" "Bourns"
			(at 119.38 247.65 0)
			(effects
				(font
					(size 1.27 1.27)
					(thickness 0.15)
				)
				(justify left bottom)
				(hide yes)
			)
		)
		(property "License" "Apache-2.0"
			(at 116.84 247.65 0)
			(effects
				(font
					(size 1.27 1.27)
					(thickness 0.15)
				)
				(justify left bottom)
				(hide yes)
			)
		)
		(property "Author" "Antmicro"
			(at 114.3 247.65 0)
			(effects
				(font
					(size 1.27 1.27)
					(thickness 0.15)
				)
				(justify left bottom)
				(hide yes)
			)
		)
		(property "Val" "10k"
			(at 144.78 266.7 90)
			(effects
				(font
					(size 1.27 1.27)
					(thickness 0.15)
				)
				(justify left)
			)
		)
		(property "Tolerance" "1%"
			(at 132.08 247.65 0)
			(effects
				(font
					(size 1.27 1.27)
				)
				(justify left bottom)
				(hide yes)
			)
		)
		(pin "1"
		)
		(pin "2"
		)
		(instances
			(project "jetson-agx-thor-baseboard"
				(path ""
					(reference "R342")
					(unit 1)
				)
			)
		)
	)
	(symbol
		(lib_id "antmicropower:+3V3")
		(at 115.57 224.79 0)
		(unit 1)
		(exclude_from_sim no)
		(in_bom yes)
		(on_board yes)
		(dnp no)
		(fields_autoplaced yes)
		(property "Reference" "#PWR0650"
			(at 130.81 224.79 0)
			(effects
				(font
					(size 1.27 1.27)
					(thickness 0.15)
				)
				(justify left bottom)
				(hide yes)
			)
		)
		(property "Value" "+3V3"
			(at 115.57 219.71 0)
			(effects
				(font
					(size 1.27 1.27)
					(thickness 0.15)
				)
			)
		)
		(property "Footprint" ""
			(at 130.81 232.41 0)
			(effects
				(font
					(size 1.27 1.27)
					(thickness 0.15)
				)
				(justify left bottom)
				(hide yes)
			)
		)
		(property "Datasheet" ""
			(at 130.81 234.95 0)
			(effects
				(font
					(size 1.27 1.27)
					(thickness 0.15)
				)
				(justify left bottom)
				(hide yes)
			)
		)
		(property "Description" ""
			(at 115.57 224.79 0)
			(effects
				(font
					(size 1.27 1.27)
				)
				(hide yes)
			)
		)
		(property "Author" "Antmicro"
			(at 130.81 227.33 0)
			(effects
				(font
					(size 1.27 1.27)
					(thickness 0.15)
				)
				(justify left bottom)
				(hide yes)
			)
		)
		(property "License" "Apache-2.0"
			(at 130.81 229.87 0)
			(effects
				(font
					(size 1.27 1.27)
					(thickness 0.15)
				)
				(justify left bottom)
				(hide yes)
			)
		)
		(pin "1"
		)
		(instances
			(project "jetson-agx-thor-baseboard"
				(path ""
					(reference "#PWR0650")
					(unit 1)
				)
			)
		)
	)
	(symbol
		(lib_id "antmicropower:GND")
		(at 205.74 242.57 0)
		(mirror y)
		(unit 1)
		(exclude_from_sim no)
		(in_bom yes)
		(on_board yes)
		(dnp no)
		(property "Reference" "#PWR029"
			(at 205.74 248.92 0)
			(effects
				(font
					(size 1.27 1.27)
				)
				(justify left bottom)
				(hide yes)
			)
		)
		(property "Value" "GND"
			(at 205.74 246.38 0)
			(effects
				(font
					(size 1.27 1.27)
				)
			)
		)
		(property "Footprint" ""
			(at 205.74 242.57 0)
			(effects
				(font
					(size 1.27 1.27)
				)
				(justify left bottom)
				(hide yes)
			)
		)
		(property "Datasheet" ""
			(at 205.74 242.57 0)
			(effects
				(font
					(size 1.27 1.27)
				)
				(justify left bottom)
				(hide yes)
			)
		)
		(property "Description" ""
			(at 205.74 242.57 0)
			(effects
				(font
					(size 1.27 1.27)
				)
				(hide yes)
			)
		)
		(property "Author" "Antmicro"
			(at 196.85 250.19 0)
			(effects
				(font
					(size 1.27 1.27)
					(thickness 0.15)
				)
				(justify left bottom)
				(hide yes)
			)
		)
		(property "License" "Apache-2.0"
			(at 196.85 252.73 0)
			(effects
				(font
					(size 1.27 1.27)
					(thickness 0.15)
				)
				(justify left bottom)
				(hide yes)
			)
		)
		(pin "1"
		)
		(instances
			(project "jetson-agx-thor-baseboard"
				(path ""
					(reference "#PWR029")
					(unit 1)
				)
			)
		)
	)
	(symbol
		(lib_id "antmicroCapacitors0402:C_100n_0402")
		(at 365.76 82.55 0)
		(mirror x)
		(unit 1)
		(exclude_from_sim no)
		(in_bom yes)
		(on_board yes)
		(dnp no)
		(property "Reference" "C332"
			(at 374.65 81.28 0)
			(effects
				(font
					(size 1.27 1.27)
				)
				(justify right)
			)
		)
		(property "Value" "C_100n_0402"
			(at 386.08 72.39 0)
			(effects
				(font
					(size 1.27 1.27)
					(thickness 0.15)
				)
				(justify left bottom)
				(hide yes)
			)
		)
		(property "Footprint" "antmicro-footprints:C_0402_1005Metric"
			(at 386.08 69.85 0)
			(effects
				(font
					(size 1.27 1.27)
					(thickness 0.15)
				)
				(justify left bottom)
				(hide yes)
			)
		)
		(property "Datasheet" "https://www.murata.com/products/productdetail?partno=GRM155R61H104KE14%23"
			(at 386.08 67.31 0)
			(effects
				(font
					(size 1.27 1.27)
					(thickness 0.15)
				)
				(justify left bottom)
				(hide yes)
			)
		)
		(property "Description" "SMD Multilayer Ceramic Capacitor, 0.1 µF, 50 V, 0402 [1005 Metric], ± 10%, X5R, GRM Series"
			(at 365.76 82.55 0)
			(effects
				(font
					(size 1.27 1.27)
				)
				(hide yes)
			)
		)
		(property "Manufacturer" "Murata"
			(at 386.08 62.23 0)
			(effects
				(font
					(size 1.27 1.27)
					(thickness 0.15)
				)
				(justify left bottom)
				(hide yes)
			)
		)
		(property "MPN" "GRM155R61H104KE14D"
			(at 386.08 64.77 0)
			(effects
				(font
					(size 1.27 1.27)
					(thickness 0.15)
				)
				(justify left bottom)
				(hide yes)
			)
		)
		(property "Val" "100n"
			(at 367.284 81.534 0)
			(effects
				(font
					(size 1.27 1.27)
					(thickness 0.15)
				)
				(justify right)
			)
		)
		(property "License" "Apache-2.0"
			(at 386.08 59.69 0)
			(effects
				(font
					(size 1.27 1.27)
					(thickness 0.15)
				)
				(justify left bottom)
				(hide yes)
			)
		)
		(property "Author" "Antmicro"
			(at 386.08 57.15 0)
			(effects
				(font
					(size 1.27 1.27)
					(thickness 0.15)
				)
				(justify left bottom)
				(hide yes)
			)
		)
		(property "Voltage" "50V"
			(at 386.08 54.61 0)
			(effects
				(font
					(size 1.27 1.27)
				)
				(justify left bottom)
				(hide yes)
			)
		)
		(property "Dielectric" "X5R"
			(at 386.08 52.07 0)
			(effects
				(font
					(size 1.27 1.27)
				)
				(justify left bottom)
				(hide yes)
			)
		)
		(pin "1"
		)
		(pin "2"
		)
		(instances
			(project "jetson-agx-thor-baseboard"
				(path ""
					(reference "C332")
					(unit 1)
				)
			)
		)
	)
	(symbol
		(lib_id "antmicroCapacitors0402:C_100n_0402")
		(at 373.38 135.89 0)
		(mirror x)
		(unit 1)
		(exclude_from_sim no)
		(in_bom yes)
		(on_board yes)
		(dnp no)
		(property "Reference" "C353"
			(at 382.016 134.62 0)
			(effects
				(font
					(size 1.27 1.27)
				)
				(justify right)
			)
		)
		(property "Value" "C_100n_0402"
			(at 393.7 125.73 0)
			(effects
				(font
					(size 1.27 1.27)
					(thickness 0.15)
				)
				(justify left bottom)
				(hide yes)
			)
		)
		(property "Footprint" "antmicro-footprints:C_0402_1005Metric"
			(at 393.7 123.19 0)
			(effects
				(font
					(size 1.27 1.27)
					(thickness 0.15)
				)
				(justify left bottom)
				(hide yes)
			)
		)
		(property "Datasheet" "https://www.murata.com/products/productdetail?partno=GRM155R61H104KE14%23"
			(at 393.7 120.65 0)
			(effects
				(font
					(size 1.27 1.27)
					(thickness 0.15)
				)
				(justify left bottom)
				(hide yes)
			)
		)
		(property "Description" "SMD Multilayer Ceramic Capacitor, 0.1 µF, 50 V, 0402 [1005 Metric], ± 10%, X5R, GRM Series"
			(at 373.38 135.89 0)
			(effects
				(font
					(size 1.27 1.27)
				)
				(hide yes)
			)
		)
		(property "Manufacturer" "Murata"
			(at 393.7 115.57 0)
			(effects
				(font
					(size 1.27 1.27)
					(thickness 0.15)
				)
				(justify left bottom)
				(hide yes)
			)
		)
		(property "MPN" "GRM155R61H104KE14D"
			(at 393.7 118.11 0)
			(effects
				(font
					(size 1.27 1.27)
					(thickness 0.15)
				)
				(justify left bottom)
				(hide yes)
			)
		)
		(property "Val" "100n"
			(at 374.904 134.874 0)
			(effects
				(font
					(size 1.27 1.27)
					(thickness 0.15)
				)
				(justify right)
			)
		)
		(property "License" "Apache-2.0"
			(at 393.7 113.03 0)
			(effects
				(font
					(size 1.27 1.27)
					(thickness 0.15)
				)
				(justify left bottom)
				(hide yes)
			)
		)
		(property "Author" "Antmicro"
			(at 393.7 110.49 0)
			(effects
				(font
					(size 1.27 1.27)
					(thickness 0.15)
				)
				(justify left bottom)
				(hide yes)
			)
		)
		(property "Voltage" "50V"
			(at 393.7 107.95 0)
			(effects
				(font
					(size 1.27 1.27)
				)
				(justify left bottom)
				(hide yes)
			)
		)
		(property "Dielectric" "X5R"
			(at 393.7 105.41 0)
			(effects
				(font
					(size 1.27 1.27)
				)
				(justify left bottom)
				(hide yes)
			)
		)
		(pin "1"
		)
		(pin "2"
		)
		(instances
			(project "jetson-agx-thor-baseboard"
				(path ""
					(reference "C353")
					(unit 1)
				)
			)
		)
	)
	(symbol
		(lib_id "antmicropower:GND")
		(at 115.57 240.03 0)
		(mirror y)
		(unit 1)
		(exclude_from_sim no)
		(in_bom yes)
		(on_board yes)
		(dnp no)
		(property "Reference" "#PWR0498"
			(at 106.68 242.57 0)
			(effects
				(font
					(size 1.27 1.27)
					(thickness 0.15)
				)
				(justify left bottom)
				(hide yes)
			)
		)
		(property "Value" "GND"
			(at 115.57 243.84 0)
			(effects
				(font
					(size 1.27 1.27)
					(thickness 0.15)
				)
			)
		)
		(property "Footprint" ""
			(at 106.68 247.65 0)
			(effects
				(font
					(size 1.27 1.27)
					(thickness 0.15)
				)
				(justify left bottom)
				(hide yes)
			)
		)
		(property "Datasheet" ""
			(at 106.68 252.73 0)
			(effects
				(font
					(size 1.27 1.27)
					(thickness 0.15)
				)
				(justify left bottom)
				(hide yes)
			)
		)
		(property "Description" ""
			(at 115.57 240.03 0)
			(effects
				(font
					(size 1.27 1.27)
				)
				(hide yes)
			)
		)
		(property "Author" "Antmicro"
			(at 106.68 247.65 0)
			(effects
				(font
					(size 1.27 1.27)
					(thickness 0.15)
				)
				(justify left bottom)
				(hide yes)
			)
		)
		(property "License" "Apache-2.0"
			(at 106.68 250.19 0)
			(effects
				(font
					(size 1.27 1.27)
					(thickness 0.15)
				)
				(justify left bottom)
				(hide yes)
			)
		)
		(pin "1"
		)
		(instances
			(project "jetson-agx-thor-baseboard"
				(path ""
					(reference "#PWR0498")
					(unit 1)
				)
			)
		)
	)
	(symbol
		(lib_id "antmicroCapacitors0402:C_100n_0402")
		(at 279.4 107.95 0)
		(mirror x)
		(unit 1)
		(exclude_from_sim no)
		(in_bom yes)
		(on_board yes)
		(dnp no)
		(property "Reference" "C337"
			(at 288.29 106.68 0)
			(effects
				(font
					(size 1.27 1.27)
				)
				(justify right)
			)
		)
		(property "Value" "C_100n_0402"
			(at 299.72 97.79 0)
			(effects
				(font
					(size 1.27 1.27)
					(thickness 0.15)
				)
				(justify left bottom)
				(hide yes)
			)
		)
		(property "Footprint" "antmicro-footprints:C_0402_1005Metric"
			(at 299.72 95.25 0)
			(effects
				(font
					(size 1.27 1.27)
					(thickness 0.15)
				)
				(justify left bottom)
				(hide yes)
			)
		)
		(property "Datasheet" "https://www.murata.com/products/productdetail?partno=GRM155R61H104KE14%23"
			(at 299.72 92.71 0)
			(effects
				(font
					(size 1.27 1.27)
					(thickness 0.15)
				)
				(justify left bottom)
				(hide yes)
			)
		)
		(property "Description" "SMD Multilayer Ceramic Capacitor, 0.1 µF, 50 V, 0402 [1005 Metric], ± 10%, X5R, GRM Series"
			(at 279.4 107.95 0)
			(effects
				(font
					(size 1.27 1.27)
				)
				(hide yes)
			)
		)
		(property "Manufacturer" "Murata"
			(at 299.72 87.63 0)
			(effects
				(font
					(size 1.27 1.27)
					(thickness 0.15)
				)
				(justify left bottom)
				(hide yes)
			)
		)
		(property "MPN" "GRM155R61H104KE14D"
			(at 299.72 90.17 0)
			(effects
				(font
					(size 1.27 1.27)
					(thickness 0.15)
				)
				(justify left bottom)
				(hide yes)
			)
		)
		(property "Val" "100n"
			(at 280.924 106.934 0)
			(effects
				(font
					(size 1.27 1.27)
					(thickness 0.15)
				)
				(justify right)
			)
		)
		(property "License" "Apache-2.0"
			(at 299.72 85.09 0)
			(effects
				(font
					(size 1.27 1.27)
					(thickness 0.15)
				)
				(justify left bottom)
				(hide yes)
			)
		)
		(property "Author" "Antmicro"
			(at 299.72 82.55 0)
			(effects
				(font
					(size 1.27 1.27)
					(thickness 0.15)
				)
				(justify left bottom)
				(hide yes)
			)
		)
		(property "Voltage" "50V"
			(at 299.72 80.01 0)
			(effects
				(font
					(size 1.27 1.27)
				)
				(justify left bottom)
				(hide yes)
			)
		)
		(property "Dielectric" "X5R"
			(at 299.72 77.47 0)
			(effects
				(font
					(size 1.27 1.27)
				)
				(justify left bottom)
				(hide yes)
			)
		)
		(pin "1"
		)
		(pin "2"
		)
		(instances
			(project "jetson-agx-thor-baseboard"
				(path ""
					(reference "C337")
					(unit 1)
				)
			)
		)
	)
	(symbol
		(lib_id "antmicroCapacitors0402:C_100n_0402")
		(at 279.4 46.99 0)
		(mirror x)
		(unit 1)
		(exclude_from_sim no)
		(in_bom yes)
		(on_board yes)
		(dnp no)
		(property "Reference" "C316"
			(at 288.29 45.72 0)
			(effects
				(font
					(size 1.27 1.27)
				)
				(justify right)
			)
		)
		(property "Value" "C_100n_0402"
			(at 299.72 36.83 0)
			(effects
				(font
					(size 1.27 1.27)
					(thickness 0.15)
				)
				(justify left bottom)
				(hide yes)
			)
		)
		(property "Footprint" "antmicro-footprints:C_0402_1005Metric"
			(at 299.72 34.29 0)
			(effects
				(font
					(size 1.27 1.27)
					(thickness 0.15)
				)
				(justify left bottom)
				(hide yes)
			)
		)
		(property "Datasheet" "https://www.murata.com/products/productdetail?partno=GRM155R61H104KE14%23"
			(at 299.72 31.75 0)
			(effects
				(font
					(size 1.27 1.27)
					(thickness 0.15)
				)
				(justify left bottom)
				(hide yes)
			)
		)
		(property "Description" "SMD Multilayer Ceramic Capacitor, 0.1 µF, 50 V, 0402 [1005 Metric], ± 10%, X5R, GRM Series"
			(at 279.4 46.99 0)
			(effects
				(font
					(size 1.27 1.27)
				)
				(hide yes)
			)
		)
		(property "Manufacturer" "Murata"
			(at 299.72 26.67 0)
			(effects
				(font
					(size 1.27 1.27)
					(thickness 0.15)
				)
				(justify left bottom)
				(hide yes)
			)
		)
		(property "MPN" "GRM155R61H104KE14D"
			(at 299.72 29.21 0)
			(effects
				(font
					(size 1.27 1.27)
					(thickness 0.15)
				)
				(justify left bottom)
				(hide yes)
			)
		)
		(property "Val" "100n"
			(at 280.924 45.974 0)
			(effects
				(font
					(size 1.27 1.27)
					(thickness 0.15)
				)
				(justify right)
			)
		)
		(property "License" "Apache-2.0"
			(at 299.72 24.13 0)
			(effects
				(font
					(size 1.27 1.27)
					(thickness 0.15)
				)
				(justify left bottom)
				(hide yes)
			)
		)
		(property "Author" "Antmicro"
			(at 299.72 21.59 0)
			(effects
				(font
					(size 1.27 1.27)
					(thickness 0.15)
				)
				(justify left bottom)
				(hide yes)
			)
		)
		(property "Voltage" "50V"
			(at 299.72 19.05 0)
			(effects
				(font
					(size 1.27 1.27)
				)
				(justify left bottom)
				(hide yes)
			)
		)
		(property "Dielectric" "X5R"
			(at 299.72 16.51 0)
			(effects
				(font
					(size 1.27 1.27)
				)
				(justify left bottom)
				(hide yes)
			)
		)
		(pin "1"
		)
		(pin "2"
		)
		(instances
			(project "jetson-agx-thor-baseboard"
				(path ""
					(reference "C316")
					(unit 1)
				)
			)
		)
	)
	(symbol
		(lib_id "antmicropower:GND")
		(at 222.25 269.24 0)
		(mirror y)
		(unit 1)
		(exclude_from_sim no)
		(in_bom yes)
		(on_board yes)
		(dnp no)
		(property "Reference" "#PWR0421"
			(at 222.25 275.59 0)
			(effects
				(font
					(size 1.27 1.27)
				)
				(justify left bottom)
				(hide yes)
			)
		)
		(property "Value" "GND"
			(at 222.25 273.05 0)
			(effects
				(font
					(size 1.27 1.27)
				)
			)
		)
		(property "Footprint" ""
			(at 222.25 269.24 0)
			(effects
				(font
					(size 1.27 1.27)
				)
				(justify left bottom)
				(hide yes)
			)
		)
		(property "Datasheet" ""
			(at 222.25 269.24 0)
			(effects
				(font
					(size 1.27 1.27)
				)
				(justify left bottom)
				(hide yes)
			)
		)
		(property "Description" ""
			(at 222.25 269.24 0)
			(effects
				(font
					(size 1.27 1.27)
				)
				(hide yes)
			)
		)
		(property "Author" "Antmicro"
			(at 213.36 276.86 0)
			(effects
				(font
					(size 1.27 1.27)
					(thickness 0.15)
				)
				(justify left bottom)
				(hide yes)
			)
		)
		(property "License" "Apache-2.0"
			(at 213.36 279.4 0)
			(effects
				(font
					(size 1.27 1.27)
					(thickness 0.15)
				)
				(justify left bottom)
				(hide yes)
			)
		)
		(pin "1"
		)
		(instances
			(project "jetson-agx-thor-baseboard"
				(path ""
					(reference "#PWR0421")
					(unit 1)
				)
			)
		)
	)
	(symbol
		(lib_id "antmicropower:+3V3_AON")
		(at 130.81 256.54 0)
		(mirror y)
		(unit 1)
		(exclude_from_sim no)
		(in_bom yes)
		(on_board yes)
		(dnp no)
		(property "Reference" "#PWR0651"
			(at 130.81 260.35 0)
			(effects
				(font
					(size 1.27 1.27)
				)
				(hide yes)
			)
		)
		(property "Value" "+1V8"
			(at 130.81 252.73 0)
			(effects
				(font
					(size 1.27 1.27)
				)
			)
		)
		(property "Footprint" ""
			(at 130.81 256.54 0)
			(effects
				(font
					(size 1.27 1.27)
				)
				(hide yes)
			)
		)
		(property "Datasheet" ""
			(at 130.81 256.54 0)
			(effects
				(font
					(size 1.27 1.27)
				)
				(hide yes)
			)
		)
		(property "Description" ""
			(at 130.81 256.54 0)
			(effects
				(font
					(size 1.27 1.27)
				)
				(hide yes)
			)
		)
		(pin "1"
		)
		(instances
			(project "jetson-agx-thor-baseboard"
				(path ""
					(reference "#PWR0651")
					(unit 1)
				)
			)
		)
	)
)
